G04 ================== begin FILE IDENTIFICATION RECORD ==================*
G04 Layout Name:  D:/<user>/Wistron_project/16315-1/gbr/16315-1.brd*
G04 Film Name:    L8*
G04 File Format:  Gerber RS274X*
G04 File Origin:  Cadence Allegro 16.5-S056*
G04 Origin Date:  Fri Jun 09 15:31:53 2017*
G04 *
G04 Layer:  VIA CLASS/L8*
G04 Layer:  PIN/L8*
G04 Layer:  ETCH/L8*
G04 Layer:  DRAWING FORMAT/LAYER_PCB_STORY*
G04 Layer:  DRAWING FORMAT/LAYER_L8*
G04 *
G04 Offset:    (0.00 0.00)*
G04 Mirror:    No*
G04 Mode:      Positive*
G04 Rotation:  0*
G04 FullContactRelief:  No*
G04 UndefLineWidth:     6.00*
G04 ================== end FILE IDENTIFICATION RECORD ====================*
%FSLAX35Y35*MOIN*%
%IR0*IPPOS*OFA0.00000B0.00000*MIA0B0*SFA1.00000B1.00000*%
%ADD11C,.02*%
%ADD13C,.03*%
%ADD12C,.022*%
%ADD14C,.042*%
%ADD15C,.034*%
%ADD10C,.028*%
%ADD16C,.048*%
%ADD17C,.01*%
%ADD18C,.004*%
%ADD19C,.005*%
%ADD20C,.006*%
%ADD21C,.00475*%
%ADD22C,.04604*%
%ADD24C,.06604*%
%ADD23C,.11704*%
%ADD25C,.13704*%
G75*
%LPD*%
G75*
G36*
G01X3937Y3004D02*
G02X3004Y3937I0J933D01*
G01Y12071D01*
G02X3714Y12323I400J0D01*
G03X7898Y8796I11444J9330D01*
G01X8000Y8739D01*
Y8000D01*
X9537D01*
X9574Y7985D01*
G03X20778Y8000I5584J13669D01*
G01X393575D01*
Y55118D01*
G02X405512Y67055I11937J0D01*
G01X408351D01*
Y62059D01*
X405512D01*
G03X398571Y55118I0J-6941D01*
G01Y3937D01*
G02X397638Y3004I-933J0D01*
G01X3937D01*
G37*
G36*
G01X8000Y34568D02*
G03X3714Y30984I7158J-12914D01*
G02X3004Y31236I-310J253D01*
G01Y461899D01*
G02X3678Y462191I400J0D01*
G03X8000Y459248I11482J12217D01*
G01Y34568D01*
G37*
G36*
G01X758787Y1460504D02*
Y1378740D01*
G02X746850Y1366803I-11937J0D01*
G01X8000D01*
Y489570D01*
G03X3678Y486627I7160J-15160D01*
G02X3004Y486919I-274J292D01*
G01Y1370866D01*
G02X3937Y1371799I933J0D01*
G01X746850D01*
G03X753791Y1378740I0J6941D01*
G01Y1464567D01*
G02X754724Y1465500I933J0D01*
G01X783465D01*
G03X790406Y1472441I0J6941D01*
G01Y1654331D01*
G02X791339Y1655264I933J0D01*
G01X799262D01*
Y1650268D01*
X795402D01*
Y1472441D01*
G02X795364Y1471483I-11937J-6D01*
G03X794795Y1468683I1484J-1759D01*
G02X783465Y1460504I-11330J3758D01*
G01X758787D01*
G37*
G36*
G01X598551Y8000D02*
X783465D01*
G02X794689Y126I0J-11937D01*
G01X796727D01*
Y-4870D01*
X791339D01*
G02X790406Y-3937I0J933D01*
G03X783465Y3004I-6941J0D01*
G01X594488D01*
G02X593555Y3937I0J933D01*
G01Y55118D01*
G03X586614Y62059I-6941J0D01*
G01X585511D01*
Y67055D01*
X586614D01*
G02X598551Y55118I0J-11937D01*
G01Y8000D01*
G37*
G36*
G01X845872Y442623D02*
X843528Y444967D01*
Y477358D01*
X845331Y479161D01*
X849595D01*
G02X849921Y478530I0J-400D01*
G03X853679I1879J-1330D01*
G02X854005Y479161I326J231D01*
G01X868641D01*
G02X868931Y478486I0J-400D01*
G03X872269I1669J-1586D01*
G02X872559Y479161I290J275D01*
G01X876646D01*
X878883Y476924D01*
Y470393D01*
G02X878440Y469996I-400J1D01*
G03Y465418I-247J-2289D01*
G02X878883Y465021I43J-398D01*
G01Y446074D01*
X875432Y442623D01*
X845872D01*
G37*
G36*
G01X1367075Y3937D02*
G02X1366142Y3004I-933J0D01*
G01X1185039D01*
G03X1178098Y-3937I0J-6941D01*
G01Y-148819D01*
G02X1177165Y-149752I-933J0D01*
G01X870079D01*
G02X869146Y-148819I0J933D01*
G01Y-16366D01*
X874142D01*
Y-144756D01*
X1173102D01*
Y-3937D01*
G02X1185039Y8000I11937J0D01*
G01X1362079D01*
Y55118D01*
G02X1374016Y67055I11937J0D01*
G01X1376944D01*
Y62059D01*
X1374016D01*
G03X1367075Y55118I0J-6941D01*
G01Y3937D01*
G37*
G36*
G01X952462Y327179D02*
X953220Y327558D01*
X954536Y328216D01*
X954594Y328210D01*
G03X952096Y333206I327J3286D01*
G01X952066Y333156D01*
X947432Y330839D01*
X947374Y330845D01*
G03X943761Y327239I-327J-3286D01*
G02X943362Y326800I-398J-39D01*
G01X940890D01*
G02X940491Y327239I-1J400D01*
G03X933919I-3286J320D01*
G02X933520Y326800I-398J-39D01*
G01X930228D01*
X930202Y326807D01*
G03X928460I-871J-3185D01*
G01X928434Y326800D01*
X907600D01*
X893222Y341178D01*
Y348965D01*
X893226Y348987D01*
G03X888738I-2244J511D01*
G01X888742Y348965D01*
Y346623D01*
G02X888060Y346340I-400J0D01*
G01X877645Y356755D01*
X877630Y356797D01*
G03X875799Y358628I-2830J-999D01*
G01X875757Y358643D01*
X861600Y372800D01*
Y411800D01*
X865300Y415500D01*
X933900D01*
X933903Y415303D01*
G03X940507I3302J51D01*
G01X940510Y415500D01*
X943742D01*
X943745Y415303D01*
G03X950349I3302J51D01*
G01X950352Y415500D01*
X959700D01*
X963300Y411900D01*
Y332100D01*
X958000Y326800D01*
X955818D01*
X955792Y326807D01*
G03X954050I-871J-3185D01*
G01X954024Y326800D01*
X952551D01*
G02X952462Y327179I0J200D01*
G37*
G36*
G01X1003681Y1450890D02*
X994483Y1460088D01*
Y1483053D01*
X997120Y1485690D01*
X1080420D01*
X1082000Y1487270D01*
Y1609593D01*
X1086719Y1614312D01*
X1137982D01*
X1145983Y1606311D01*
Y1459747D01*
X1137126Y1450890D01*
X1003681D01*
G37*
G36*
G01X1080573Y1488483D02*
X1079590Y1487500D01*
X995968D01*
X994302Y1489166D01*
Y1534567D01*
X995775Y1536040D01*
X1078460D01*
X1080573Y1533927D01*
Y1488483D01*
G37*
G36*
G01X1120176Y333156D02*
X1115542Y330839D01*
X1115484Y330845D01*
G03X1111855Y327598I-327J-3286D01*
G01X1111853Y327400D01*
X1108619D01*
X1108617Y327598D01*
G03X1102013I-3302J-39D01*
G01X1102011Y327400D01*
X1069800D01*
X1063000Y334200D01*
Y409500D01*
X1065600Y412100D01*
X1093750D01*
G02X1094149Y411669I0J-400D01*
G03X1100733I3292J-252D01*
G02X1101132Y412100I399J31D01*
G01X1104754D01*
X1104770Y412097D01*
G03X1105860I545J3257D01*
G01X1105876Y412100D01*
X1114596D01*
X1114612Y412097D01*
G03X1115702I545J3257D01*
G01X1115718Y412100D01*
X1119340D01*
G02X1119739Y411669I0J-400D01*
G03X1126323I3292J-252D01*
G02X1126722Y412100I399J31D01*
G01X1130000D01*
X1133900Y408200D01*
Y330900D01*
X1130400Y327400D01*
X1122709D01*
G02X1122530Y328158I0J400D01*
G01X1122646Y328216D01*
X1122704Y328210D01*
G03X1120206Y333205I327J3286D01*
G01X1120176Y333156D01*
G37*
G36*
G01X1567055Y55118D02*
Y8000D01*
X1889065D01*
G03X1900305I5620J13654D01*
G01X1926843D01*
Y1366803D01*
X1168110D01*
G02X1156173Y1378740I0J11937D01*
G01Y1468504D01*
G02X1168110Y1480441I11937J0D01*
G01X1212472D01*
Y1650268D01*
X1071589D01*
Y1655264D01*
X1216535D01*
G02X1217468Y1654331I0J-933D01*
G01Y1476378D01*
G02X1216535Y1475445I-933J0D01*
G01X1168110D01*
G03X1161169Y1468504I0J-6941D01*
G01Y1378740D01*
G03X1168110Y1371799I6941J0D01*
G01X1930906D01*
G02X1931839Y1370866I0J-933D01*
G01Y3937D01*
G02X1930906Y3004I-933J0D01*
G01X1562992D01*
G02X1562059Y3937I0J933D01*
G01Y55118D01*
G03X1555118Y62059I-6941J0D01*
G01X1554061D01*
Y67055D01*
X1555118D01*
G02X1567055Y55118I0J-11937D01*
G37*
G36*
G01X1887038Y888836D02*
G02X1886707Y889460I0J400D01*
G03X1885929Y892756I-1907J1290D01*
G02X1885840Y893385I196J349D01*
G03X1883885Y897280I-1640J1615D01*
G02X1883430Y897677I-55J396D01*
G01Y931836D01*
X1886416Y934822D01*
X1908664D01*
X1911351Y932135D01*
Y899682D01*
G02X1910715Y899359I-400J0D01*
G03X1909329Y895198I-1357J-1859D01*
G02X1909672Y894601I-5J-400D01*
G03X1911193Y891218I2004J-1132D01*
G01X1911351Y891184D01*
Y890628D01*
X1909559Y888836D01*
X1904724D01*
X1904690Y888993D01*
G03X1900192I-2249J-493D01*
G01X1900158Y888836D01*
X1887038D01*
G37*
%LPC*%
G75*
G36*
G01X867544Y448673D02*
G02X865094Y448675I-1227J-1948D01*
G03Y449352I-213J339D01*
G02X864022Y451419I1227J1948D01*
G03X863382Y451759I-399J21D01*
G02X863445Y455392I-1382J1841D01*
G03X864078Y455584I251J311D01*
G02X865113Y456886I2198J-685D01*
G03Y457577I-202J345D01*
G02X867441Y457576I1165J1985D01*
G03Y456885I202J-346D01*
G02X868012Y453388I-1165J-1985D01*
G03X868018Y452855I301J-263D01*
G02X867544Y449350I-1697J-1555D01*
G03Y448673I213J-338D01*
G37*
G36*
G01X1123366Y1586608D02*
G03X1122697I-334J-220D01*
G02Y1590558I-3012J1975D01*
G03X1123366I335J220D01*
G02Y1586608I3012J-1975D01*
G37*
G36*
G01X1105138D02*
G03X1104469I-334J-220D01*
G02Y1590558I-3012J1975D01*
G03X1105138I334J220D01*
G02Y1586608I3012J-1975D01*
G37*
G36*
G01X1095005Y1553378D02*
G03X1094469I-268J-297D01*
G02X1091290Y1556706I-1543J1708D01*
G03Y1557268I-284J281D01*
G02X1094469Y1560596I1636J1620D01*
G03X1095005I268J297D01*
G02X1098184Y1557268I1543J-1708D01*
G03Y1556706I284J-281D01*
G02X1095005Y1553378I-1636J-1620D01*
G37*
G36*
G01X1097575Y1533801D02*
G03Y1533239I284J-281D01*
G02X1094301I-1637J-1619D01*
G03Y1533801I-284J281D01*
G02X1097575I1637J1619D01*
G37*
G36*
G01X1092455D02*
G03Y1533239I284J-281D01*
G02X1089181I-1637J-1619D01*
G03Y1533801I-284J281D01*
G02X1092455I1637J1619D01*
G37*
G36*
G01X1075050Y1453527D02*
G03X1074458I-296J-269D01*
G02Y1456623I-1704J1548D01*
G03X1075050I296J269D01*
G02Y1453527I1704J-1548D01*
G37*
G36*
G01X1046358Y1456623D02*
G03X1046950I296J269D01*
G02Y1453527I1704J-1548D01*
G03X1046358I-296J-269D01*
G02Y1456623I-1704J1548D01*
G37*
G36*
G01X1018558D02*
G03X1019150I296J269D01*
G02Y1453527I1704J-1548D01*
G03X1018558I-296J-269D01*
G02Y1456623I-1704J1548D01*
G37*
G36*
G01X1895026Y893075D02*
G03X1894360I-333J-221D01*
G02Y895625I-1917J1275D01*
G03X1895026I333J221D01*
G02Y893075I1917J-1275D01*
G37*
G54D22*
X846400Y469300D03*
X852000Y454200D03*
X871487Y463589D03*
X887100Y359100D03*
X887500Y378495D03*
X874807Y375193D03*
X1904000Y921000D03*
G54D24*
X954921Y339371D03*
X929331Y331496D03*
X947047Y335434D03*
X954921Y411417D03*
Y403543D03*
X929331Y411417D03*
Y403543D03*
X947047Y407480D03*
X937205D03*
Y391732D03*
X1097441Y331496D03*
Y403543D03*
X1105315Y407480D03*
Y391732D03*
X1123031Y339371D03*
X1115157Y335434D03*
X1123031Y403543D03*
X1115157Y407480D03*
G54D23*
X942126Y346457D03*
G54D25*
X1110236D03*
%LPD*%
G75*
G54D10*
X24508Y5500D03*
X5500Y61492D03*
Y56492D03*
Y51492D03*
Y46492D03*
Y41492D03*
Y66492D03*
Y81492D03*
Y76492D03*
Y96492D03*
Y91492D03*
Y86492D03*
Y71492D03*
Y101492D03*
Y111492D03*
Y116492D03*
Y106492D03*
Y126492D03*
Y121492D03*
Y141492D03*
Y151492D03*
Y161492D03*
Y156492D03*
Y146492D03*
Y131492D03*
Y136492D03*
Y181492D03*
Y191492D03*
Y201492D03*
Y211492D03*
Y171492D03*
Y206492D03*
Y196492D03*
Y176492D03*
Y166492D03*
Y186492D03*
Y231492D03*
Y241492D03*
Y251492D03*
Y261492D03*
Y221492D03*
Y256492D03*
Y246492D03*
Y226492D03*
Y216492D03*
Y236492D03*
Y281492D03*
Y291492D03*
Y301492D03*
Y271492D03*
Y306492D03*
Y296492D03*
Y286492D03*
Y276492D03*
Y266492D03*
Y331492D03*
Y341492D03*
Y351492D03*
Y311492D03*
Y321492D03*
Y356492D03*
Y346492D03*
Y336492D03*
Y326492D03*
Y316492D03*
Y381492D03*
Y391492D03*
Y401492D03*
Y361492D03*
Y371492D03*
Y406492D03*
Y396492D03*
Y386492D03*
Y376492D03*
Y366492D03*
Y451492D03*
Y441492D03*
Y431492D03*
Y421492D03*
Y411492D03*
Y416492D03*
Y436492D03*
Y446492D03*
Y426492D03*
Y501492D03*
Y456492D03*
Y496492D03*
Y531492D03*
Y551492D03*
Y541492D03*
Y521492D03*
Y511492D03*
Y536492D03*
Y546492D03*
Y506492D03*
Y516492D03*
Y526492D03*
Y581492D03*
Y591492D03*
Y571492D03*
Y561492D03*
Y586492D03*
Y596492D03*
Y556492D03*
Y566492D03*
Y576492D03*
Y631492D03*
Y641492D03*
Y621492D03*
Y611492D03*
Y601492D03*
Y636492D03*
Y646492D03*
Y606492D03*
Y616492D03*
Y626492D03*
Y681492D03*
Y691492D03*
Y671492D03*
Y661492D03*
Y651492D03*
Y686492D03*
Y696492D03*
Y656492D03*
Y666492D03*
Y676492D03*
Y731492D03*
Y741492D03*
Y721492D03*
Y711492D03*
Y701492D03*
Y736492D03*
Y706492D03*
Y716492D03*
Y726492D03*
Y781492D03*
Y791492D03*
Y771492D03*
Y761492D03*
Y751492D03*
Y786492D03*
Y746492D03*
Y756492D03*
Y766492D03*
Y776492D03*
Y831492D03*
Y841492D03*
Y821492D03*
Y811492D03*
Y801492D03*
Y836492D03*
Y796492D03*
Y806492D03*
Y816492D03*
Y826492D03*
Y881492D03*
Y871492D03*
Y861492D03*
Y851492D03*
Y886492D03*
Y846492D03*
Y856492D03*
Y866492D03*
Y876492D03*
Y931492D03*
Y921492D03*
Y911492D03*
Y901492D03*
Y891492D03*
Y936492D03*
Y896492D03*
Y906492D03*
Y916492D03*
Y926492D03*
Y976492D03*
Y981492D03*
Y986492D03*
Y966492D03*
Y956492D03*
Y961492D03*
Y971492D03*
Y951492D03*
Y941492D03*
Y946492D03*
Y991492D03*
Y996492D03*
Y1001492D03*
Y1006492D03*
Y1026492D03*
Y1016492D03*
Y1011492D03*
Y1021492D03*
Y1031492D03*
Y1036492D03*
Y1066492D03*
Y1056492D03*
Y1046492D03*
Y1041492D03*
Y1051492D03*
Y1061492D03*
Y1071492D03*
Y1081492D03*
Y1076492D03*
Y1121492D03*
Y1131492D03*
Y1111492D03*
Y1101492D03*
Y1091492D03*
Y1086492D03*
Y1096492D03*
Y1106492D03*
Y1116492D03*
Y1126492D03*
Y1171492D03*
Y1161492D03*
Y1151492D03*
Y1141492D03*
Y1136492D03*
Y1146492D03*
Y1156492D03*
Y1166492D03*
Y1176492D03*
Y1221492D03*
Y1211492D03*
Y1201492D03*
Y1191492D03*
Y1181492D03*
Y1186492D03*
Y1196492D03*
Y1206492D03*
Y1216492D03*
Y1226492D03*
Y1271492D03*
Y1261492D03*
Y1251492D03*
Y1241492D03*
Y1231492D03*
Y1236492D03*
Y1246492D03*
Y1256492D03*
Y1266492D03*
Y1276492D03*
Y1321492D03*
Y1311492D03*
Y1301492D03*
Y1291492D03*
Y1281492D03*
Y1286492D03*
Y1296492D03*
Y1306492D03*
Y1316492D03*
X8983Y1368303D03*
X13983D03*
X18983D03*
X23983D03*
X5500Y1361492D03*
Y1351492D03*
Y1341492D03*
Y1331492D03*
Y1336492D03*
Y1346492D03*
Y1356492D03*
Y1326492D03*
X29508Y5500D03*
X39508D03*
X34508D03*
X44508D03*
X64508D03*
X69508D03*
X54508D03*
X49508D03*
X59508D03*
X28983Y1368303D03*
X33983D03*
X38983D03*
X43983D03*
X48983D03*
X53983D03*
X58983D03*
X63983D03*
X68983D03*
X114508Y5500D03*
X119508D03*
X104508D03*
X94508D03*
X84508D03*
X74508D03*
X79508D03*
X89508D03*
X99508D03*
X109508D03*
X73983Y1368303D03*
X78983D03*
X83983D03*
X88983D03*
X93983D03*
X98983D03*
X107374Y1369303D03*
X112374D03*
X117374D03*
X134508Y5500D03*
X124508D03*
X129508D03*
X169508D03*
X159508D03*
X149508D03*
X139508D03*
X154508D03*
X164508D03*
X144508D03*
X122374Y1369303D03*
X127374D03*
X132374D03*
X137374D03*
X142374D03*
X147374D03*
X152374D03*
X157374D03*
X162374D03*
X167374D03*
X209508Y5500D03*
X199508D03*
X189508D03*
X179508D03*
X204508D03*
X214508D03*
X174508D03*
X184508D03*
X194508D03*
X172374Y1369303D03*
X177374D03*
X182374D03*
X187374D03*
X192374D03*
X197374D03*
X202374D03*
X207374D03*
X212374D03*
X217374D03*
X259508Y5500D03*
X249508D03*
X239508D03*
X229508D03*
X219508D03*
X224508D03*
X234508D03*
X244508D03*
X254508D03*
X264508D03*
X222374Y1369303D03*
X227374D03*
X232374D03*
X237374D03*
X242374D03*
X247374D03*
X252374D03*
X257374D03*
X262374D03*
X309508Y5500D03*
X299508D03*
X289508D03*
X279508D03*
X269508D03*
X304508D03*
X314508D03*
X274508D03*
X284508D03*
X294508D03*
X267374Y1369303D03*
X272374D03*
X277374D03*
X282374D03*
X287374D03*
X292374D03*
X297374D03*
X302374D03*
X307374D03*
X312374D03*
X359508Y5500D03*
X349508D03*
X339508D03*
X329508D03*
X319508D03*
X324508D03*
X334508D03*
X344508D03*
X354508D03*
X333983Y1368303D03*
X338983D03*
X343983D03*
X348983D03*
X353983D03*
X358983D03*
X363983D03*
X317374Y1369303D03*
X322374D03*
X327374D03*
X395075Y18639D03*
Y13639D03*
X389508Y5500D03*
X379508D03*
X369508D03*
X364508D03*
X374508D03*
X384508D03*
X394508D03*
X395075Y43639D03*
Y38639D03*
Y33639D03*
Y28639D03*
Y23639D03*
X399000Y62000D03*
X396000Y55500D03*
X396075Y50248D03*
X368983Y1368303D03*
X373983D03*
X378983D03*
X383983D03*
X388983D03*
X393983D03*
X398983D03*
X403983D03*
X408983D03*
X413983D03*
X418983D03*
X423983D03*
X428983D03*
X433983D03*
X438983D03*
X443983D03*
X448983D03*
X453983D03*
X458983D03*
X463983D03*
X468983D03*
X473983D03*
X478983D03*
X483983D03*
X488983D03*
X493983D03*
X498983D03*
X503983D03*
X508983D03*
X517374Y1369303D03*
X522374D03*
X527374D03*
X532374D03*
X537374D03*
X542374D03*
X547374D03*
X552374D03*
X557374D03*
X597051Y7699D03*
Y12699D03*
Y17699D03*
X604146Y5500D03*
X597051Y22699D03*
Y27699D03*
Y32699D03*
Y37699D03*
Y42699D03*
X589000Y64000D03*
X594000Y61500D03*
X596000Y56500D03*
X596051Y51090D03*
X567374Y1369303D03*
X572374D03*
X577374D03*
X582374D03*
X587374D03*
X592374D03*
X597374D03*
X602374D03*
X562374D03*
X609146Y5500D03*
X619146D03*
X614146D03*
X629146D03*
X639146D03*
X649146D03*
X654146D03*
X644146D03*
X634146D03*
X624146D03*
X629192Y593186D03*
X617374Y1369303D03*
X622374D03*
X627374D03*
X632374D03*
X637374D03*
X642374D03*
X647374D03*
X652374D03*
X607374D03*
X612374D03*
X679146Y5500D03*
X689146D03*
X694146D03*
X684146D03*
X659146D03*
X669146D03*
X664146D03*
X674146D03*
X699146D03*
X667374Y1369303D03*
X672374D03*
X677374D03*
X682374D03*
X687374D03*
X692374D03*
X697374D03*
X702374D03*
X657374D03*
X662374D03*
X749146Y5500D03*
X709146D03*
X719146D03*
X729146D03*
X739146D03*
X744146D03*
X734146D03*
X724146D03*
X714146D03*
X704146D03*
X747374Y1369303D03*
X742374D03*
X717374D03*
X722374D03*
X727374D03*
X732374D03*
X737374D03*
X707374D03*
X712374D03*
X795969Y-1374D03*
X759146Y5500D03*
X769146D03*
X774146D03*
X764146D03*
X754146D03*
X779146D03*
X755500Y1374500D03*
X752500Y1370500D03*
X757287Y1380873D03*
Y1385873D03*
Y1390873D03*
Y1395873D03*
Y1400873D03*
Y1405873D03*
Y1410873D03*
Y1415873D03*
Y1420873D03*
Y1425873D03*
Y1430873D03*
Y1435873D03*
Y1440873D03*
Y1445873D03*
X766156Y1462004D03*
X771156D03*
X790500Y1466500D03*
X786000Y1463500D03*
X756287Y1459264D03*
Y1454264D03*
X779547Y1463004D03*
X792902Y1477964D03*
Y1487964D03*
Y1497964D03*
Y1507964D03*
Y1517964D03*
Y1512964D03*
Y1472964D03*
Y1482964D03*
Y1492964D03*
Y1502964D03*
Y1562964D03*
Y1527964D03*
Y1537964D03*
Y1547964D03*
Y1557964D03*
Y1567964D03*
Y1522964D03*
Y1532964D03*
Y1542964D03*
Y1552964D03*
Y1612964D03*
Y1602964D03*
Y1592964D03*
Y1582964D03*
Y1572964D03*
Y1577964D03*
Y1587964D03*
Y1597964D03*
Y1607964D03*
X797902Y1652964D03*
X792902D03*
Y1642964D03*
Y1632964D03*
Y1622964D03*
Y1627964D03*
Y1637964D03*
Y1647964D03*
Y1617964D03*
X872642Y-140575D03*
Y-135575D03*
Y-130575D03*
Y-125575D03*
X890264Y-147256D03*
X880264D03*
X875264D03*
X885264D03*
X895264D03*
X872642Y-80575D03*
Y-120575D03*
Y-115575D03*
Y-110575D03*
Y-105575D03*
Y-100575D03*
Y-95575D03*
Y-90575D03*
Y-85575D03*
Y-30575D03*
Y-35575D03*
Y-40575D03*
Y-45575D03*
Y-50575D03*
Y-55575D03*
Y-60575D03*
Y-65575D03*
Y-70575D03*
Y-75575D03*
Y-20575D03*
Y-25575D03*
X940264Y-147256D03*
X930264D03*
X925264D03*
X935264D03*
X920264D03*
X910264D03*
X900264D03*
X905264D03*
X915264D03*
X960264D03*
X950264D03*
X955264D03*
X965264D03*
X945264D03*
X990264D03*
X980264D03*
X970264D03*
X975264D03*
X985264D03*
X1010264D03*
X1000264D03*
X1005264D03*
X1015264D03*
X995264D03*
X1040264D03*
X1030264D03*
X1020264D03*
X1025264D03*
X1035264D03*
X1060264D03*
X1050264D03*
X1055264D03*
X1065264D03*
X1045264D03*
X1080264D03*
X1070264D03*
X1075264D03*
X1085264D03*
X1078098Y1652768D03*
X1073098D03*
X1083098D03*
X1088098D03*
X1110264Y-147256D03*
X1100264D03*
X1090264D03*
X1105264D03*
X1095264D03*
X1130264D03*
X1120264D03*
X1115264D03*
X1125264D03*
X1135264D03*
X1093098Y1652768D03*
X1133098D03*
X1123098D03*
X1113098D03*
X1103098D03*
X1108098D03*
X1118098D03*
X1128098D03*
X1098098D03*
X1170264Y-147256D03*
X1155264D03*
X1175602Y-137594D03*
Y-127594D03*
X1160264Y-147256D03*
X1150264D03*
X1140264D03*
X1145264D03*
X1175602Y-132594D03*
Y-142594D03*
X1165264Y-147256D03*
X1175602Y-117594D03*
Y-107594D03*
Y-97594D03*
Y-87594D03*
Y-77594D03*
Y-82594D03*
Y-92594D03*
Y-102594D03*
Y-112594D03*
Y-122594D03*
Y-67594D03*
Y-57594D03*
Y-47594D03*
Y-37594D03*
Y-32594D03*
Y-42594D03*
Y-52594D03*
Y-62594D03*
Y-72594D03*
Y-17594D03*
Y-27594D03*
X1180500Y4000D03*
X1176500Y-500D03*
X1175602Y-22594D03*
Y-12594D03*
Y-7594D03*
X1162000Y1371500D03*
X1169783Y1369303D03*
X1179783D03*
X1174783D03*
X1184783D03*
X1158673Y1417067D03*
Y1407067D03*
Y1397067D03*
Y1387067D03*
Y1377067D03*
Y1412067D03*
Y1402067D03*
Y1392067D03*
Y1382067D03*
Y1422067D03*
Y1442067D03*
Y1452067D03*
X1158500Y1468500D03*
X1158673Y1457067D03*
Y1447067D03*
Y1437067D03*
Y1427067D03*
Y1462067D03*
Y1432067D03*
X1161000Y1474500D03*
X1166673Y1477941D03*
X1171673D03*
X1181673D03*
X1176673D03*
X1143098Y1652768D03*
X1183098D03*
X1173098D03*
X1163098D03*
X1153098D03*
X1158098D03*
X1168098D03*
X1178098D03*
X1138098D03*
X1148098D03*
X1191382Y5500D03*
X1196382D03*
X1186382D03*
X1201382D03*
X1211382D03*
X1221382D03*
X1231382D03*
X1226382D03*
X1216382D03*
X1206382D03*
X1199783Y1369303D03*
X1209783D03*
X1219783D03*
X1229783D03*
X1189783D03*
X1224783D03*
X1214783D03*
X1204783D03*
X1194783D03*
X1191673Y1477941D03*
X1201673D03*
X1214972Y1482642D03*
Y1517642D03*
Y1487642D03*
Y1497642D03*
Y1507642D03*
Y1512642D03*
Y1502642D03*
Y1492642D03*
X1206673Y1477941D03*
X1196673D03*
X1186673D03*
X1211673D03*
X1214972Y1567642D03*
Y1527642D03*
Y1537642D03*
Y1547642D03*
Y1557642D03*
Y1562642D03*
Y1552642D03*
Y1542642D03*
Y1532642D03*
Y1522642D03*
Y1577642D03*
Y1587642D03*
Y1597642D03*
Y1607642D03*
Y1612642D03*
Y1602642D03*
Y1592642D03*
Y1582642D03*
Y1572642D03*
Y1617642D03*
Y1627642D03*
Y1637642D03*
X1213098Y1652768D03*
X1193098D03*
X1203098D03*
X1208098D03*
X1214972Y1642642D03*
Y1632642D03*
X1188098Y1652768D03*
X1198098D03*
X1214972Y1622642D03*
Y1647642D03*
X1251382Y5500D03*
X1261382D03*
X1271382D03*
X1281382D03*
X1276382D03*
X1266382D03*
X1256382D03*
X1241382D03*
X1246382D03*
X1236382D03*
X1249783Y1369303D03*
X1259783D03*
X1269783D03*
X1279783D03*
X1239783D03*
X1274783D03*
X1264783D03*
X1254783D03*
X1234783D03*
X1244783D03*
X1301382Y5500D03*
X1311382D03*
X1296382D03*
X1316382D03*
X1306382D03*
X1291382D03*
X1286382D03*
X1326382D03*
X1321382D03*
X1299783Y1369303D03*
X1309783D03*
X1319783D03*
X1329783D03*
X1289783D03*
X1324783D03*
X1314783D03*
X1304783D03*
X1294783D03*
X1284783D03*
X1363579Y19821D03*
Y14821D03*
Y9821D03*
X1351382Y5500D03*
X1356382D03*
X1346382D03*
X1336382D03*
X1341382D03*
X1331382D03*
X1363579Y44821D03*
Y39821D03*
Y34821D03*
Y29821D03*
Y24821D03*
X1374000Y64500D03*
X1363579Y51618D03*
X1349783Y1369303D03*
X1359783D03*
X1369783D03*
X1339783D03*
X1374783D03*
X1364783D03*
X1354783D03*
X1344783D03*
X1334783D03*
X1386500Y534400D03*
X1399783Y1369303D03*
X1409783D03*
X1419783D03*
X1379783D03*
X1389783D03*
X1404783D03*
X1414783D03*
X1424783D03*
X1394783D03*
X1384783D03*
X1449783D03*
X1459783D03*
X1469783D03*
X1429783D03*
X1439783D03*
X1444783D03*
X1454783D03*
X1464783D03*
X1474783D03*
X1434783D03*
X1499783D03*
X1509783D03*
X1519783D03*
X1479783D03*
X1489783D03*
X1494783D03*
X1484783D03*
X1504783D03*
X1514783D03*
X1565555Y16517D03*
X1568030Y5500D03*
X1565555Y21517D03*
Y26517D03*
Y31517D03*
Y36517D03*
Y41517D03*
X1557000Y64500D03*
X1561500Y62000D03*
X1564000Y57500D03*
X1564555Y52124D03*
X1549783Y1369303D03*
X1559783D03*
X1569783D03*
X1529783D03*
X1539783D03*
X1524783D03*
X1534783D03*
X1544783D03*
X1554783D03*
X1564783D03*
X1603030Y5500D03*
X1613030D03*
X1573030D03*
X1583030D03*
X1593030D03*
X1618030D03*
X1608030D03*
X1598030D03*
X1588030D03*
X1578030D03*
X1614783Y1369303D03*
X1604783D03*
X1599783D03*
X1609783D03*
X1619783D03*
X1579783D03*
X1589783D03*
X1574783D03*
X1584783D03*
X1594783D03*
X1653030Y5500D03*
X1663030D03*
X1623030D03*
X1633030D03*
X1643030D03*
X1668030D03*
X1658030D03*
X1648030D03*
X1638030D03*
X1628030D03*
X1664783Y1369303D03*
X1654783D03*
X1644783D03*
X1634783D03*
X1624783D03*
X1649783D03*
X1659783D03*
X1629783D03*
X1639783D03*
X1703030Y5500D03*
X1713030D03*
X1673030D03*
X1683030D03*
X1693030D03*
X1718030D03*
X1708030D03*
X1698030D03*
X1688030D03*
X1678030D03*
X1714783Y1369303D03*
X1704783D03*
X1694783D03*
X1684783D03*
X1674783D03*
X1699783D03*
X1709783D03*
X1669783D03*
X1679783D03*
X1689783D03*
X1753030Y5500D03*
X1763030D03*
X1723030D03*
X1733030D03*
X1743030D03*
X1758030D03*
X1748030D03*
X1738030D03*
X1728030D03*
X1764783Y1369303D03*
X1754783D03*
X1744783D03*
X1734783D03*
X1724783D03*
X1749783D03*
X1759783D03*
X1719783D03*
X1729783D03*
X1739783D03*
X1778030Y5500D03*
X1793030D03*
X1803030D03*
X1813030D03*
X1808030D03*
X1798030D03*
X1783030D03*
X1788030D03*
X1773030D03*
X1768030D03*
X1804783Y1369303D03*
X1794783D03*
X1784783D03*
X1774783D03*
X1799783D03*
X1809783D03*
X1769783D03*
X1779783D03*
X1789783D03*
X1843030Y5500D03*
X1853030D03*
X1863030D03*
X1838030D03*
X1858030D03*
X1848030D03*
X1823030D03*
X1833030D03*
X1828030D03*
X1818030D03*
X1854783Y1369303D03*
X1844783D03*
X1834783D03*
X1824783D03*
X1814783D03*
X1849783D03*
X1859783D03*
X1819783D03*
X1829783D03*
X1839783D03*
X1878030Y5500D03*
X1883030D03*
X1873030D03*
X1868030D03*
X1909030D03*
X1888030D03*
X1904783Y1369303D03*
X1894783D03*
X1884783D03*
X1874783D03*
X1864783D03*
X1899783D03*
X1909783D03*
X1869783D03*
X1879783D03*
X1889783D03*
X1929343Y16525D03*
Y11525D03*
Y6525D03*
X1914030Y5500D03*
X1919030D03*
X1924030D03*
X1929343Y46525D03*
Y41525D03*
Y36525D03*
Y31525D03*
Y26525D03*
Y21525D03*
Y66525D03*
Y61525D03*
Y56525D03*
Y51525D03*
Y116525D03*
Y111525D03*
Y106525D03*
Y101525D03*
Y96525D03*
Y91525D03*
Y86525D03*
Y81525D03*
Y76525D03*
Y71525D03*
Y121525D03*
Y126525D03*
Y136525D03*
Y146525D03*
Y156525D03*
Y161525D03*
Y151525D03*
Y141525D03*
Y131525D03*
Y176525D03*
Y186525D03*
Y196525D03*
Y206525D03*
Y166525D03*
Y211525D03*
Y201525D03*
Y191525D03*
Y181525D03*
Y171525D03*
Y226525D03*
Y236525D03*
Y246525D03*
Y256525D03*
Y216525D03*
Y261525D03*
Y251525D03*
Y241525D03*
Y231525D03*
Y221525D03*
Y276525D03*
Y286525D03*
Y296525D03*
Y306525D03*
Y266525D03*
Y301525D03*
Y291525D03*
Y281525D03*
Y271525D03*
Y326525D03*
Y336525D03*
Y346525D03*
Y356525D03*
Y316525D03*
Y351525D03*
Y341525D03*
Y331525D03*
Y321525D03*
Y311525D03*
Y376525D03*
Y386525D03*
Y396525D03*
Y406525D03*
Y366525D03*
Y401525D03*
Y391525D03*
Y381525D03*
Y371525D03*
Y361525D03*
Y426525D03*
Y436525D03*
Y446525D03*
Y416525D03*
Y451525D03*
Y441525D03*
Y431525D03*
Y421525D03*
Y411525D03*
Y476525D03*
Y486525D03*
Y496525D03*
Y456525D03*
Y466525D03*
Y501525D03*
Y491525D03*
Y481525D03*
Y471525D03*
Y461525D03*
Y526525D03*
Y536525D03*
Y546525D03*
Y506525D03*
Y516525D03*
Y551525D03*
Y541525D03*
Y531525D03*
Y521525D03*
Y511525D03*
Y576525D03*
Y586525D03*
Y596525D03*
Y556525D03*
Y566525D03*
Y591525D03*
Y581525D03*
Y571525D03*
Y561525D03*
Y626525D03*
Y636525D03*
Y646525D03*
Y606525D03*
Y616525D03*
Y641525D03*
Y631525D03*
Y621525D03*
Y611525D03*
Y601525D03*
Y676525D03*
Y686525D03*
Y696525D03*
Y656525D03*
Y666525D03*
Y691525D03*
Y681525D03*
Y671525D03*
Y661525D03*
Y651525D03*
Y726525D03*
Y736525D03*
Y706525D03*
Y716525D03*
Y741525D03*
Y731525D03*
Y721525D03*
Y711525D03*
Y701525D03*
Y776525D03*
Y786525D03*
Y746525D03*
Y756525D03*
Y766525D03*
Y791525D03*
Y781525D03*
Y771525D03*
Y761525D03*
Y751525D03*
Y826525D03*
Y836525D03*
Y796525D03*
Y806525D03*
Y816525D03*
Y841525D03*
Y831525D03*
Y821525D03*
Y811525D03*
Y801525D03*
Y876525D03*
Y886525D03*
Y846525D03*
Y856525D03*
Y866525D03*
Y881525D03*
Y871525D03*
Y861525D03*
Y851525D03*
Y926525D03*
Y896525D03*
Y906525D03*
Y916525D03*
Y931525D03*
Y921525D03*
Y911525D03*
Y901525D03*
Y891525D03*
Y936525D03*
Y973863D03*
Y978863D03*
Y983863D03*
Y951525D03*
Y956525D03*
Y961525D03*
Y966525D03*
Y946525D03*
Y941525D03*
Y988863D03*
Y993863D03*
Y998863D03*
Y1003863D03*
Y1008863D03*
Y1033863D03*
Y1028863D03*
Y1023863D03*
Y1018863D03*
Y1013863D03*
Y1073863D03*
Y1083863D03*
Y1043863D03*
Y1053863D03*
Y1063863D03*
Y1078863D03*
Y1068863D03*
Y1058863D03*
Y1048863D03*
Y1038863D03*
Y1123863D03*
Y1093863D03*
Y1103863D03*
Y1113863D03*
Y1128863D03*
Y1118863D03*
Y1108863D03*
Y1098863D03*
Y1088863D03*
Y1173863D03*
Y1133863D03*
Y1143863D03*
Y1153863D03*
Y1163863D03*
Y1178863D03*
Y1168863D03*
Y1158863D03*
Y1148863D03*
Y1138863D03*
Y1223863D03*
Y1183863D03*
Y1193863D03*
Y1203863D03*
Y1213863D03*
Y1228863D03*
Y1218863D03*
Y1208863D03*
Y1198863D03*
Y1188863D03*
Y1273863D03*
Y1233863D03*
Y1243863D03*
Y1253863D03*
Y1263863D03*
Y1268863D03*
Y1258863D03*
Y1248863D03*
Y1238863D03*
Y1323863D03*
Y1283863D03*
Y1293863D03*
Y1303863D03*
Y1313863D03*
Y1318863D03*
Y1308863D03*
Y1298863D03*
Y1288863D03*
Y1278863D03*
Y1333863D03*
Y1343863D03*
Y1353863D03*
X1924783Y1369303D03*
X1914783D03*
X1919783D03*
X1929343Y1358863D03*
Y1348863D03*
Y1338863D03*
Y1328863D03*
Y1363863D03*
G54D20*
G01X394744Y-485863D02*
X395618Y-484988D01*
X396273Y-483530D01*
X396710Y-481487D01*
X396273Y-479738D01*
X395400Y-478571D01*
X393871Y-477696D01*
X387976D01*
Y-495196D01*
X395181D01*
X396710Y-494030D01*
X397583Y-492279D01*
X398020Y-490238D01*
X397583Y-488196D01*
X396273Y-486446D01*
X394744Y-485863D01*
X387976D01*
G01X407441Y-495196D02*
Y-483530D01*
G01Y-485863D02*
X408533Y-484696D01*
X409625Y-483821D01*
X411153Y-483530D01*
X412244Y-483821D01*
X413555Y-484696D01*
G01X423413Y-500446D02*
X424723Y-501029D01*
X426470Y-500446D01*
X427561Y-499280D01*
X428435Y-497821D01*
X429744Y-493155D01*
X432583Y-483530D01*
G01X425596D02*
X429744Y-493155D01*
G01X448991Y-484988D02*
X447463Y-483821D01*
X446153Y-483530D01*
X444406Y-484113D01*
X443096Y-485279D01*
X442223Y-487321D01*
X442004Y-489363D01*
X442223Y-491405D01*
X443096Y-493155D01*
X444406Y-494613D01*
X446153Y-495196D01*
X447681Y-494613D01*
X448991Y-493446D01*
G01X459723Y-487321D02*
X466710D01*
X466055Y-485279D01*
X464963Y-484113D01*
X463435Y-483530D01*
X461906Y-483821D01*
X460596Y-484696D01*
X459723Y-486738D01*
X459286Y-488488D01*
Y-490238D01*
X459723Y-491988D01*
X460815Y-493738D01*
X462125Y-494904D01*
X463653Y-495196D01*
X465181Y-494613D01*
X466710Y-492863D01*
G01X502801Y-479155D02*
X501491Y-478279D01*
X499963Y-477696D01*
X498216D01*
X496251Y-478571D01*
X494723Y-480029D01*
X493631Y-481780D01*
X492758Y-484696D01*
X492539Y-487321D01*
X492976Y-489946D01*
X493631Y-491696D01*
X494941Y-493446D01*
X496470Y-494613D01*
X497998Y-495196D01*
X499526D01*
X501055Y-494613D01*
X502365Y-493738D01*
X503457Y-492572D01*
G01X519428Y-495196D02*
Y-483530D01*
G01Y-485571D02*
X518555Y-484405D01*
X517244Y-483821D01*
X515716Y-483530D01*
X514188Y-484113D01*
X512878Y-485279D01*
X512004Y-487029D01*
X511568Y-489363D01*
X512004Y-491696D01*
X512878Y-493446D01*
X514188Y-494613D01*
X515716Y-495196D01*
X517244Y-494904D01*
X518555Y-494030D01*
X519428Y-492863D01*
G01X529286Y-495196D02*
Y-483530D01*
G01Y-486446D02*
X530160Y-484988D01*
X531470Y-483821D01*
X533216Y-483530D01*
X534744Y-483821D01*
X536055Y-484988D01*
X536710Y-487029D01*
Y-495196D01*
G01X545913Y-500446D02*
X547223Y-501029D01*
X548970Y-500446D01*
X550061Y-499280D01*
X550935Y-497821D01*
X552244Y-493155D01*
X555083Y-483530D01*
G01X548096D02*
X552244Y-493155D01*
G01X567998Y-495196D02*
X566688Y-494904D01*
X565378Y-493738D01*
X564504Y-491696D01*
X564068Y-489363D01*
X564504Y-487029D01*
X565378Y-484988D01*
X566688Y-483821D01*
X567998Y-483530D01*
X569308Y-483821D01*
X570618Y-484988D01*
X571491Y-487029D01*
X571710Y-489363D01*
X571491Y-491696D01*
X570618Y-493738D01*
X569308Y-494904D01*
X567998Y-495196D01*
G01X581786D02*
Y-483530D01*
G01Y-486446D02*
X582660Y-484988D01*
X583970Y-483821D01*
X585716Y-483530D01*
X587244Y-483821D01*
X588555Y-484988D01*
X589210Y-487029D01*
Y-495196D01*
G01X616350D02*
Y-477696D01*
X624646D01*
G01X621590Y-486154D02*
X616350D01*
G01X637998Y-495779D02*
X637561Y-495488D01*
Y-494904D01*
X637998Y-494613D01*
X638435Y-494904D01*
Y-495488D01*
X637998Y-495779D01*
G01X650695Y-495196D02*
Y-477696D01*
X655061D01*
X656808Y-478571D01*
X658118Y-479738D01*
X659210Y-481487D01*
X660083Y-483530D01*
X660301Y-486446D01*
X660083Y-489363D01*
X659210Y-491405D01*
X658118Y-493155D01*
X656808Y-494321D01*
X655061Y-495196D01*
X650695D01*
G01X668631D02*
Y-477696D01*
X673871D01*
X675618Y-478571D01*
X676928Y-480613D01*
X677365Y-482946D01*
X676928Y-485279D01*
X675836Y-487029D01*
X673871Y-487905D01*
X668631D01*
G01X692244Y-485863D02*
X693118Y-484988D01*
X693773Y-483530D01*
X694210Y-481487D01*
X693773Y-479738D01*
X692900Y-478571D01*
X691371Y-477696D01*
X685476D01*
Y-495196D01*
X692681D01*
X694210Y-494030D01*
X695083Y-492279D01*
X695520Y-490238D01*
X695083Y-488196D01*
X693773Y-486446D01*
X692244Y-485863D01*
X685476D01*
G01X501071Y-450196D02*
Y-432696D01*
X506748Y-447279D01*
X512425Y-432696D01*
Y-450196D01*
G01X524248D02*
X522938Y-449904D01*
X521628Y-448738D01*
X520754Y-446696D01*
X520318Y-444363D01*
X520754Y-442029D01*
X521628Y-439988D01*
X522938Y-438821D01*
X524248Y-438530D01*
X525558Y-438821D01*
X526868Y-439988D01*
X527741Y-442029D01*
X527960Y-444363D01*
X527741Y-446696D01*
X526868Y-448738D01*
X525558Y-449904D01*
X524248Y-450196D01*
G01X545678Y-432696D02*
Y-450196D01*
G01Y-447572D02*
X544805Y-449030D01*
X543494Y-449904D01*
X541966Y-450196D01*
X540220Y-449613D01*
X538910Y-448155D01*
X538036Y-446405D01*
X537818Y-444363D01*
X538036Y-442321D01*
X538910Y-440571D01*
X540220Y-439113D01*
X541966Y-438530D01*
X543494Y-438821D01*
X544586Y-439405D01*
X545678Y-440571D01*
G01X555973Y-442321D02*
X562960D01*
X562305Y-440279D01*
X561213Y-439113D01*
X559685Y-438530D01*
X558156Y-438821D01*
X556846Y-439696D01*
X555973Y-441738D01*
X555536Y-443488D01*
Y-445238D01*
X555973Y-446988D01*
X557065Y-448738D01*
X558375Y-449904D01*
X559903Y-450196D01*
X561431Y-449613D01*
X562960Y-447863D01*
G01X576748Y-450196D02*
Y-432696D01*
G01X754448Y-495196D02*
Y-477696D01*
X751828Y-481196D01*
G01Y-495196D02*
X757068D01*
G01X767800Y-487905D02*
X769328Y-485863D01*
X770638Y-484696D01*
X772385Y-484113D01*
X773913Y-484696D01*
X775005Y-485863D01*
X775878Y-487613D01*
X776096Y-489654D01*
X775878Y-491405D01*
X775005Y-493155D01*
X773694Y-494613D01*
X772166Y-495196D01*
X770420Y-494613D01*
X768891Y-492863D01*
X768018Y-490238D01*
X767800Y-487321D01*
X768236Y-483530D01*
X768891Y-481487D01*
X769983Y-479446D01*
X771511Y-477988D01*
X773040Y-477696D01*
X774568Y-478279D01*
X775660Y-479738D01*
G01X784645Y-491696D02*
X785954Y-493738D01*
X787701Y-494904D01*
X789666Y-495196D01*
X791413Y-494904D01*
X793160Y-493446D01*
X794251Y-491696D01*
X794470Y-489946D01*
X794033Y-487905D01*
X792505Y-486446D01*
X790976Y-485863D01*
X789011D01*
G01X790976D02*
X792286Y-484988D01*
X793378Y-483530D01*
X793815Y-481780D01*
X793378Y-480029D01*
X792286Y-478571D01*
X790321Y-477696D01*
X788356Y-477988D01*
X786391Y-479155D01*
G01X806948Y-495196D02*
Y-477696D01*
X804328Y-481196D01*
G01Y-495196D02*
X809568D01*
G01X819645Y-492572D02*
X820954Y-494030D01*
X822483Y-494904D01*
X824448Y-495196D01*
X826413Y-494613D01*
X827941Y-493446D01*
X829033Y-491405D01*
X829251Y-489071D01*
X828815Y-486738D01*
X827723Y-485279D01*
X826194Y-484113D01*
X824666Y-483821D01*
X823138Y-484113D01*
X821173Y-485279D01*
X821828Y-477696D01*
X827723D01*
G01X741331Y-450196D02*
Y-432696D01*
X746571D01*
X748318Y-433571D01*
X749628Y-435613D01*
X750065Y-437946D01*
X749628Y-440279D01*
X748536Y-442029D01*
X746571Y-442905D01*
X741331D01*
G01X768001Y-434155D02*
X766691Y-433279D01*
X765163Y-432696D01*
X763416D01*
X761451Y-433571D01*
X759923Y-435029D01*
X758831Y-436780D01*
X757958Y-439696D01*
X757739Y-442321D01*
X758176Y-444946D01*
X758831Y-446696D01*
X760141Y-448446D01*
X761670Y-449613D01*
X763198Y-450196D01*
X764726D01*
X766255Y-449613D01*
X767565Y-448738D01*
X768657Y-447572D01*
G01X782444Y-440863D02*
X783318Y-439988D01*
X783973Y-438530D01*
X784410Y-436487D01*
X783973Y-434738D01*
X783100Y-433571D01*
X781571Y-432696D01*
X775676D01*
Y-450196D01*
X782881D01*
X784410Y-449030D01*
X785283Y-447279D01*
X785720Y-445238D01*
X785283Y-443196D01*
X783973Y-441446D01*
X782444Y-440863D01*
X775676D01*
G01X791648Y-456029D02*
X804748D01*
G01X810676Y-450196D02*
Y-432696D01*
X820720Y-450196D01*
Y-432696D01*
G01X833198Y-450196D02*
X831451Y-449904D01*
X829923Y-448738D01*
X828613Y-446988D01*
X827739Y-444946D01*
X827303Y-442613D01*
Y-440279D01*
X827739Y-437946D01*
X828613Y-435904D01*
X829923Y-434155D01*
X831451Y-432988D01*
X833198Y-432696D01*
X834944Y-432988D01*
X836473Y-434155D01*
X837783Y-435904D01*
X838657Y-437946D01*
X839093Y-440279D01*
Y-442613D01*
X838657Y-444946D01*
X837783Y-446988D01*
X836473Y-448738D01*
X834944Y-449904D01*
X833198Y-450196D01*
G01X884039Y-432696D02*
X889498Y-450196D01*
X894957Y-432696D01*
G01X911365Y-450196D02*
X902631D01*
Y-432696D01*
X911365D01*
G01X907871Y-441154D02*
X902631D01*
G01X920131Y-450196D02*
Y-432696D01*
X925590D01*
X927336Y-433571D01*
X928428Y-434738D01*
X928865Y-437071D01*
X928428Y-439405D01*
X927118Y-440863D01*
X925590Y-441738D01*
X920131D01*
G01X925590D02*
X928865Y-450196D01*
G01X941998Y-450779D02*
X941561Y-450488D01*
Y-449904D01*
X941998Y-449613D01*
X942435Y-449904D01*
Y-450488D01*
X941998Y-450779D01*
G01X915748Y-495196D02*
Y-477696D01*
X913128Y-481196D01*
G01Y-495196D02*
X918368D01*
G01X1082981Y-432696D02*
Y-450196D01*
X1091715D01*
G01X1108778D02*
Y-438530D01*
G01Y-440571D02*
X1107905Y-439405D01*
X1106594Y-438821D01*
X1105066Y-438530D01*
X1103538Y-439113D01*
X1102228Y-440279D01*
X1101354Y-442029D01*
X1100918Y-444363D01*
X1101354Y-446696D01*
X1102228Y-448446D01*
X1103538Y-449613D01*
X1105066Y-450196D01*
X1106594Y-449904D01*
X1107905Y-449030D01*
X1108778Y-447863D01*
G01X1117763Y-455446D02*
X1119073Y-456029D01*
X1120820Y-455446D01*
X1121911Y-454280D01*
X1122785Y-452821D01*
X1124094Y-448155D01*
X1126933Y-438530D01*
G01X1119946D02*
X1124094Y-448155D01*
G01X1136573Y-442321D02*
X1143560D01*
X1142905Y-440279D01*
X1141813Y-439113D01*
X1140285Y-438530D01*
X1138756Y-438821D01*
X1137446Y-439696D01*
X1136573Y-441738D01*
X1136136Y-443488D01*
Y-445238D01*
X1136573Y-446988D01*
X1137665Y-448738D01*
X1138975Y-449904D01*
X1140503Y-450196D01*
X1142031Y-449613D01*
X1143560Y-447863D01*
G01X1154291Y-450196D02*
Y-438530D01*
G01Y-440863D02*
X1155383Y-439696D01*
X1156475Y-438821D01*
X1158003Y-438530D01*
X1159094Y-438821D01*
X1160405Y-439696D01*
G01X1135465Y-477696D02*
Y-495196D01*
X1126731D01*
G01X1113598D02*
X1112070Y-494904D01*
X1110323Y-494030D01*
X1109231Y-492572D01*
X1108795Y-490529D01*
X1109231Y-488488D01*
X1110541Y-486738D01*
X1112506Y-485863D01*
X1114690D01*
X1116000Y-485279D01*
X1117092Y-483821D01*
X1117528Y-481780D01*
X1116873Y-479738D01*
X1115345Y-478279D01*
X1113598Y-477696D01*
X1111852Y-478279D01*
X1110323Y-479738D01*
X1109668Y-481780D01*
X1110105Y-483821D01*
X1111196Y-485279D01*
X1112506Y-485863D01*
X1114690D01*
X1116655Y-486738D01*
X1117965Y-488488D01*
X1118401Y-490529D01*
X1117965Y-492572D01*
X1116873Y-494030D01*
X1115126Y-494904D01*
X1113598Y-495196D01*
G01X1312898D02*
X1311151Y-494904D01*
X1309623Y-493738D01*
X1308313Y-491988D01*
X1307439Y-489946D01*
X1307003Y-487613D01*
Y-485279D01*
X1307439Y-482946D01*
X1308313Y-480904D01*
X1309623Y-479155D01*
X1311151Y-477988D01*
X1312898Y-477696D01*
X1314644Y-477988D01*
X1316173Y-479155D01*
X1317483Y-480904D01*
X1318357Y-482946D01*
X1318793Y-485279D01*
Y-487613D01*
X1318357Y-489946D01*
X1317483Y-491988D01*
X1316173Y-493738D01*
X1314644Y-494904D01*
X1312898Y-495196D01*
G01X1314644Y-490529D02*
X1317265Y-495196D01*
G01X1325595Y-477696D02*
Y-490238D01*
X1326468Y-492863D01*
X1328215Y-494613D01*
X1330398Y-495196D01*
X1332581Y-494613D01*
X1334328Y-492863D01*
X1335201Y-490238D01*
Y-477696D01*
G01X1345278D02*
X1350518D01*
G01X1347898D02*
Y-495196D01*
G01X1345278D02*
X1350518D01*
G01X1360376D02*
Y-477696D01*
X1370420Y-495196D01*
Y-477696D01*
G01X1387701Y-479155D02*
X1386391Y-478279D01*
X1384863Y-477696D01*
X1383116D01*
X1381151Y-478571D01*
X1379623Y-480029D01*
X1378531Y-481780D01*
X1377658Y-484696D01*
X1377439Y-487321D01*
X1377876Y-489946D01*
X1378531Y-491696D01*
X1379841Y-493446D01*
X1381370Y-494613D01*
X1382898Y-495196D01*
X1384426D01*
X1385955Y-494613D01*
X1387265Y-493738D01*
X1388357Y-492572D01*
G01X1400398Y-495196D02*
Y-487321D01*
X1396031Y-477696D01*
G01X1404765D02*
X1400398Y-487321D01*
G01X1290595Y-450196D02*
Y-432696D01*
X1294961D01*
X1296708Y-433571D01*
X1298018Y-434738D01*
X1299110Y-436487D01*
X1299983Y-438530D01*
X1300201Y-441446D01*
X1299983Y-444363D01*
X1299110Y-446405D01*
X1298018Y-448155D01*
X1296708Y-449321D01*
X1294961Y-450196D01*
X1290595D01*
G01X1309623Y-442321D02*
X1316610D01*
X1315955Y-440279D01*
X1314863Y-439113D01*
X1313335Y-438530D01*
X1311806Y-438821D01*
X1310496Y-439696D01*
X1309623Y-441738D01*
X1309186Y-443488D01*
Y-445238D01*
X1309623Y-446988D01*
X1310715Y-448738D01*
X1312025Y-449904D01*
X1313553Y-450196D01*
X1315081Y-449613D01*
X1316610Y-447863D01*
G01X1327123Y-448155D02*
X1328215Y-449321D01*
X1329743Y-450196D01*
X1331053D01*
X1332363Y-449613D01*
X1333236Y-448738D01*
X1333673Y-447572D01*
X1333455Y-445821D01*
X1332581Y-444946D01*
X1328651Y-443196D01*
X1327778Y-441154D01*
X1328215Y-439696D01*
X1329088Y-438821D01*
X1330398Y-438530D01*
X1331708Y-438821D01*
X1333018Y-439696D01*
G01X1347898Y-438530D02*
Y-450196D01*
G01Y-433863D02*
X1347461Y-433571D01*
Y-432988D01*
X1347898Y-432696D01*
X1348335Y-432988D01*
Y-433571D01*
X1347898Y-433863D01*
G01X1362341Y-454571D02*
X1363870Y-455738D01*
X1365616Y-456029D01*
X1367144Y-455738D01*
X1368455Y-454280D01*
X1369328Y-452238D01*
Y-438530D01*
G01Y-440863D02*
X1368455Y-439696D01*
X1367144Y-438821D01*
X1365616Y-438530D01*
X1363870Y-439113D01*
X1362778Y-440279D01*
X1361904Y-442321D01*
X1361468Y-444363D01*
X1361686Y-446113D01*
X1362560Y-448155D01*
X1363870Y-449613D01*
X1365616Y-450196D01*
X1366926Y-449904D01*
X1368455Y-448738D01*
X1369328Y-447572D01*
G01X1379186Y-450196D02*
Y-438530D01*
G01Y-441446D02*
X1380060Y-439988D01*
X1381370Y-438821D01*
X1383116Y-438530D01*
X1384644Y-438821D01*
X1385955Y-439988D01*
X1386610Y-442029D01*
Y-450196D01*
G01X1397123Y-442321D02*
X1404110D01*
X1403455Y-440279D01*
X1402363Y-439113D01*
X1400835Y-438530D01*
X1399306Y-438821D01*
X1397996Y-439696D01*
X1397123Y-441738D01*
X1396686Y-443488D01*
Y-445238D01*
X1397123Y-446988D01*
X1398215Y-448738D01*
X1399525Y-449904D01*
X1401053Y-450196D01*
X1402581Y-449613D01*
X1404110Y-447863D01*
G01X1414841Y-450196D02*
Y-438530D01*
G01Y-440863D02*
X1415933Y-439696D01*
X1417025Y-438821D01*
X1418553Y-438530D01*
X1419644Y-438821D01*
X1420955Y-439696D01*
G01X1461598Y-477696D02*
X1459851Y-478279D01*
X1458541Y-479738D01*
X1457668Y-481487D01*
X1457013Y-483821D01*
X1456795Y-486446D01*
X1457013Y-489071D01*
X1457668Y-491405D01*
X1458541Y-493155D01*
X1459851Y-494613D01*
X1461598Y-495196D01*
X1463344Y-494613D01*
X1464655Y-493155D01*
X1465528Y-491405D01*
X1466183Y-489071D01*
X1466401Y-486446D01*
X1466183Y-483821D01*
X1465528Y-481487D01*
X1464655Y-479738D01*
X1463344Y-478279D01*
X1461598Y-477696D01*
G01X1474950Y-487905D02*
X1476478Y-485863D01*
X1477788Y-484696D01*
X1479535Y-484113D01*
X1481063Y-484696D01*
X1482155Y-485863D01*
X1483028Y-487613D01*
X1483246Y-489654D01*
X1483028Y-491405D01*
X1482155Y-493155D01*
X1480844Y-494613D01*
X1479316Y-495196D01*
X1477570Y-494613D01*
X1476041Y-492863D01*
X1475168Y-490238D01*
X1474950Y-487321D01*
X1475386Y-483530D01*
X1476041Y-481487D01*
X1477133Y-479446D01*
X1478661Y-477988D01*
X1480190Y-477696D01*
X1481718Y-478279D01*
X1482810Y-479738D01*
G01X1492668Y-495779D02*
X1500528Y-477696D01*
G01X1514098D02*
X1512351Y-478279D01*
X1511041Y-479738D01*
X1510168Y-481487D01*
X1509513Y-483821D01*
X1509295Y-486446D01*
X1509513Y-489071D01*
X1510168Y-491405D01*
X1511041Y-493155D01*
X1512351Y-494613D01*
X1514098Y-495196D01*
X1515844Y-494613D01*
X1517155Y-493155D01*
X1518028Y-491405D01*
X1518683Y-489071D01*
X1518901Y-486446D01*
X1518683Y-483821D01*
X1518028Y-481487D01*
X1517155Y-479738D01*
X1515844Y-478279D01*
X1514098Y-477696D01*
G01X1527886Y-493155D02*
X1529415Y-494613D01*
X1531161Y-495196D01*
X1532908Y-494613D01*
X1534436Y-492863D01*
X1535528Y-490238D01*
X1535965Y-487613D01*
Y-484405D01*
X1535528Y-481780D01*
X1534436Y-479446D01*
X1533126Y-478279D01*
X1531598Y-477696D01*
X1529851Y-478279D01*
X1528541Y-479446D01*
X1527668Y-481196D01*
X1527231Y-483530D01*
X1527668Y-485571D01*
X1528760Y-487613D01*
X1530070Y-488780D01*
X1531598Y-489071D01*
X1533344Y-488488D01*
X1534655Y-487029D01*
X1535965Y-484405D01*
G01X1545168Y-495779D02*
X1553028Y-477696D01*
G01X1562450Y-480613D02*
X1563760Y-478863D01*
X1565288Y-477988D01*
X1567035Y-477696D01*
X1569218Y-478279D01*
X1570746Y-479738D01*
X1571183Y-481487D01*
X1570965Y-483238D01*
X1570091Y-484696D01*
X1565725Y-487613D01*
X1563760Y-489654D01*
X1562450Y-492572D01*
X1562013Y-495196D01*
X1571183D01*
G01X1584098Y-477696D02*
X1582351Y-478279D01*
X1581041Y-479738D01*
X1580168Y-481487D01*
X1579513Y-483821D01*
X1579295Y-486446D01*
X1579513Y-489071D01*
X1580168Y-491405D01*
X1581041Y-493155D01*
X1582351Y-494613D01*
X1584098Y-495196D01*
X1585844Y-494613D01*
X1587155Y-493155D01*
X1588028Y-491405D01*
X1588683Y-489071D01*
X1588901Y-486446D01*
X1588683Y-483821D01*
X1588028Y-481487D01*
X1587155Y-479738D01*
X1585844Y-478279D01*
X1584098Y-477696D01*
G01X1601598Y-495196D02*
Y-477696D01*
X1598978Y-481196D01*
G01Y-495196D02*
X1604218D01*
G01X1618661D02*
X1619098Y-491405D01*
X1619753Y-488196D01*
X1620626Y-485279D01*
X1621718Y-482071D01*
X1623465Y-477696D01*
X1614731D01*
G01X1509295Y-450196D02*
Y-432696D01*
X1513661D01*
X1515408Y-433571D01*
X1516718Y-434738D01*
X1517810Y-436487D01*
X1518683Y-438530D01*
X1518901Y-441446D01*
X1518683Y-444363D01*
X1517810Y-446405D01*
X1516718Y-448155D01*
X1515408Y-449321D01*
X1513661Y-450196D01*
X1509295D01*
G01X1535528D02*
Y-438530D01*
G01Y-440571D02*
X1534655Y-439405D01*
X1533344Y-438821D01*
X1531816Y-438530D01*
X1530288Y-439113D01*
X1528978Y-440279D01*
X1528104Y-442029D01*
X1527668Y-444363D01*
X1528104Y-446696D01*
X1528978Y-448446D01*
X1530288Y-449613D01*
X1531816Y-450196D01*
X1533344Y-449904D01*
X1534655Y-449030D01*
X1535528Y-447863D01*
G01X1549098Y-432696D02*
Y-450196D01*
G01X1546041Y-438530D02*
X1552155D01*
G01X1563323Y-442321D02*
X1570310D01*
X1569655Y-440279D01*
X1568563Y-439113D01*
X1567035Y-438530D01*
X1565506Y-438821D01*
X1564196Y-439696D01*
X1563323Y-441738D01*
X1562886Y-443488D01*
Y-445238D01*
X1563323Y-446988D01*
X1564415Y-448738D01*
X1565725Y-449904D01*
X1567253Y-450196D01*
X1568781Y-449613D01*
X1570310Y-447863D01*
G54D11*
G01X363248Y-425196D02*
Y-505196D01*
G01D02*
X1639148D01*
G01X359248Y-409196D02*
G02I-12000J0D01*
G01X354098D02*
G02I-6850J0D01*
G01X347248Y-425196D02*
Y-393196D01*
G01X363248Y-425196D02*
X1639148D01*
G01X363248Y-460696D02*
X1639148D01*
G01X363248Y-409196D02*
X331248D01*
G01X343962Y181161D02*
X353034Y172089D01*
Y167099D01*
X357921Y162212D01*
X388648D01*
X408877Y182441D01*
X468472D01*
G01D02*
X476216Y174697D01*
X508166D01*
X526262Y192793D01*
X574456D01*
X581009Y186240D01*
X593977D01*
X598236Y181981D01*
G01X580279Y512831D02*
X577079Y516031D01*
X556160D01*
X553460Y513331D01*
X553279D01*
G01X598236Y181981D02*
X603256Y176961D01*
X712400D01*
X716600Y181161D01*
G01X580279Y512831D02*
X589496Y522048D01*
Y553490D01*
X629192Y593186D01*
G01X720748Y-425196D02*
Y-505196D01*
G01X716600Y181161D02*
X724444D01*
X728556Y177049D01*
X757643D01*
X767405Y186811D01*
Y210364D01*
G01D02*
X820940D01*
X874800Y264224D01*
Y355798D01*
G01X863800Y1309876D02*
X778951D01*
X769728Y1319099D01*
Y1325747D01*
G01X936959Y1360143D02*
X915081Y1338265D01*
X898822D01*
X873433Y1312876D01*
X781551D01*
X772900Y1321527D01*
Y1328550D01*
G01X858248Y-425196D02*
Y-505196D01*
G01X863800Y1309876D02*
X874676D01*
X899793Y1334993D01*
X930530D01*
X951525Y1355988D01*
Y1369107D01*
G01X872164Y1350464D02*
X872181Y1350481D01*
Y1354764D01*
G01D02*
X873259Y1355842D01*
Y1365805D01*
G01X873918Y1411149D02*
X866336Y1418731D01*
X866335D01*
X864335Y1420731D01*
Y1487102D01*
X872191Y1494958D01*
Y1506173D01*
X882732Y1516714D01*
Y1538472D01*
X889300Y1545040D01*
Y1551000D01*
G01X973248Y-425196D02*
Y-505196D01*
G01X1070155Y1116103D02*
X1083355D01*
G01X1271648Y-425196D02*
Y-505196D01*
G01X1373553Y700994D02*
X1378106D01*
X1421200Y657900D01*
Y630430D01*
X1436213Y615417D01*
G01X1384475Y255839D02*
X1393133Y247181D01*
Y232491D01*
X1421500Y204124D01*
Y176964D01*
X1428732Y169732D01*
X1428782D01*
X1430363Y168151D01*
Y168101D01*
X1436213Y162251D01*
Y159247D01*
X1436204D01*
G01X1447700Y579600D02*
X1419500Y551400D01*
Y543300D01*
X1413400Y537200D01*
X1389300D01*
X1386500Y534400D01*
G01X1441648Y-425196D02*
Y-505196D01*
G01X1447700Y579600D02*
X1451240Y576060D01*
X1471660D01*
X1474700Y579100D01*
G01X1491594Y508098D02*
X1491000Y508692D01*
Y619930D01*
X1458713Y652217D01*
G01X1560425Y162661D02*
Y165875D01*
X1542400Y183900D01*
Y205436D01*
X1499775Y248061D01*
G01X1639148Y-425196D02*
Y-505196D01*
G01X1667148Y-409196D02*
G02I-12000J0D01*
G01X1661998D02*
G02I-6850J0D01*
G01X1655148Y-425196D02*
Y-393196D01*
G01X1671148Y-409196D02*
X1639148D01*
G01X1746400Y244561D02*
X1763700D01*
X1797950Y210311D01*
Y173561D01*
X1808850Y162661D01*
G01X1805250Y1067973D02*
Y1070130D01*
X1795400Y1079980D01*
Y1106373D01*
X1748100Y1153673D01*
G01X1766721Y720500D02*
X1792000Y695221D01*
Y632267D01*
X1808850Y615417D01*
X127988Y190242D03*
Y185742D03*
Y638498D03*
Y642998D03*
Y1091254D03*
Y1095754D03*
X252200Y190242D03*
Y185742D03*
Y638498D03*
Y642998D03*
Y1091254D03*
Y1095754D03*
X376413Y190242D03*
Y185742D03*
Y638498D03*
Y642998D03*
Y1091254D03*
Y1095754D03*
X500625Y190242D03*
Y185742D03*
Y638498D03*
Y642998D03*
Y1091254D03*
Y1095754D03*
X624838Y190242D03*
Y185742D03*
Y638498D03*
Y642998D03*
Y1091254D03*
Y1095754D03*
X749051Y190242D03*
Y185742D03*
Y638498D03*
Y642998D03*
Y1091254D03*
Y1095754D03*
X1274900Y182823D03*
X1270400D03*
X1261250Y167823D03*
X1256750D03*
X1402713Y185742D03*
Y190242D03*
X1380963Y167823D03*
X1385463D03*
G54D21*
G01X323813Y133722D02*
X325491Y135400D01*
X399293D01*
X432016Y168123D01*
X516871D01*
X533442Y184694D01*
X539584D01*
G01X314439Y133669D02*
X319081Y138311D01*
X392142D01*
X424563Y170732D01*
X510763D01*
X527574Y187543D01*
X542155D01*
G01X450984Y100591D02*
Y101548D01*
X453580Y104144D01*
Y136611D01*
X476817Y159848D01*
X498649D01*
X500307Y158190D01*
X541346D01*
X550543Y167387D01*
X566271D01*
G01X458071Y96654D02*
X455455Y99270D01*
Y124147D01*
X461392Y130084D01*
X469775D01*
X495443Y155752D01*
X563036D01*
X568726Y161442D01*
X613723D01*
X664252Y110913D01*
X685147D01*
X694093Y119859D01*
X735015D01*
X878038Y262882D01*
Y327670D01*
X890982Y340614D01*
Y349498D01*
G01X450984Y114764D02*
Y117111D01*
X448746Y119349D01*
Y135731D01*
X475339Y162324D01*
X499674D01*
X501192Y160806D01*
X539831D01*
X549257Y170232D01*
X595738D01*
X602053Y163917D01*
X639990D01*
X663449Y140458D01*
Y115606D01*
G01X436811Y100591D02*
X439800Y103580D01*
Y130286D01*
X474313Y164799D01*
X500700D01*
X502218Y163281D01*
X538805D01*
X548232Y172708D01*
X596763D01*
X603079Y166392D01*
X722692D01*
X728800Y172500D01*
X763188D01*
G01X848032Y1632284D02*
X846884D01*
X844600Y1630000D01*
Y1585400D01*
X809991Y1550791D01*
Y1385963D01*
X788728Y1364700D01*
X515457D01*
X510504Y1359747D01*
X422373D01*
G01X848032Y1626772D02*
X850128D01*
X851500Y1625400D01*
Y1587700D01*
X813243Y1549443D01*
Y1384615D01*
X791228Y1362600D01*
X517600D01*
X511522Y1356522D01*
X418922D01*
G01X479331Y100591D02*
X483341D01*
X489346Y94586D01*
X506081D01*
X512213Y100718D01*
Y122307D01*
X515036Y125130D01*
X518929D01*
X521886Y128087D01*
X528810D01*
X534518Y133795D01*
X540937D01*
X548390Y141248D01*
X571755D01*
X595105Y117898D01*
X609795D01*
X648968Y78725D01*
X661298D01*
X709990Y30033D01*
X898535D01*
X923201Y5367D01*
X951606D01*
X1010650Y64411D01*
Y67650D01*
G01X465157Y120276D02*
X498158Y153277D01*
X564062D01*
X569752Y158967D01*
X612090D01*
X672841Y98216D01*
X719298D01*
X872796Y251714D01*
G01X550197Y114764D02*
X545781Y119180D01*
Y126333D01*
X552496Y133048D01*
X568253D01*
X630776Y70525D01*
X657898D01*
X709323Y19100D01*
X875879D01*
X877487Y17492D01*
X898434D01*
X926492Y-10566D01*
X946521D01*
X956303Y-784D01*
X1038954D01*
X1068912Y-30742D01*
X1079455D01*
G01X536024Y106103D02*
X533515Y108612D01*
Y125607D01*
X536753Y128845D01*
X542989D01*
X550442Y136298D01*
X569703D01*
X593672Y112329D01*
X607929D01*
G01X536024Y100591D02*
X531400Y105215D01*
Y127176D01*
X535544Y131320D01*
X541963D01*
X549416Y138773D01*
X570729D01*
X594079Y115423D01*
X608040D01*
X608658Y114805D01*
X608954D01*
X647509Y76250D01*
X660272D01*
X709222Y27300D01*
X897334D01*
X921742Y2892D01*
X952632D01*
X999690Y49950D01*
X1010650D01*
G01X550197Y100591D02*
X554664Y105058D01*
Y123012D01*
X559367Y127715D01*
X565475D01*
X627540Y65650D01*
X655736D01*
X707489Y13897D01*
X874185D01*
X875704Y12378D01*
X895454D01*
X923301Y-15469D01*
X948515D01*
X958324Y-5660D01*
X1036730D01*
X1067277Y-36207D01*
X1081495D01*
X1082615Y-35087D01*
X1107187D01*
X1111254Y-31020D01*
G01X550197Y106103D02*
X552700Y108606D01*
Y124621D01*
X557788Y129709D01*
X566133D01*
X628567Y67275D01*
X656480D01*
X708233Y15522D01*
X874859D01*
X876378Y14003D01*
X896128D01*
X923975Y-13844D01*
X947841D01*
X957651Y-4034D01*
X1037606D01*
X1067935Y-34363D01*
X1081040D01*
X1081942Y-33461D01*
X1102872D01*
X1105328Y-31005D01*
G01X543110Y102166D02*
X540195Y105081D01*
Y123399D01*
X551469Y134673D01*
X569029D01*
X631552Y72150D01*
X658572D01*
X708035Y22687D01*
X895975D01*
X927115Y-8453D01*
X928138D01*
G01X550197Y120276D02*
X547785Y122688D01*
Y125685D01*
X553523Y131423D01*
X567579D01*
X630102Y68900D01*
X657224D01*
X708977Y17147D01*
X875533D01*
X876813Y15867D01*
X897560D01*
X925646Y-12219D01*
X947167D01*
X956977Y-2409D01*
X1038280D01*
X1068555Y-32684D01*
X1080420D01*
X1081268Y-31836D01*
X1100415D01*
X1101246Y-31005D01*
G01X855118Y1650394D02*
X859675Y1645837D01*
Y1590273D01*
X859676Y1590272D01*
Y1588720D01*
X859675Y1588719D01*
Y1588501D01*
X820000Y1548826D01*
Y1383666D01*
X793334Y1357000D01*
X538826D01*
X536000Y1359826D01*
G01X855118Y1644882D02*
X857800Y1642200D01*
Y1590127D01*
X817525Y1549852D01*
Y1384692D01*
X792659Y1359826D01*
X541362D01*
G01X607929Y112329D02*
X646483Y73775D01*
X659246D01*
X708284Y24737D01*
X896396D01*
X920957Y176D01*
X922604D01*
X922687Y93D01*
G01X869292Y1650394D02*
X869244D01*
X864980Y1646130D01*
Y1586800D01*
X837475Y1559295D01*
Y1527010D01*
X829400Y1518935D01*
Y1381093D01*
X778660Y1330353D01*
Y1326740D01*
X781730Y1323670D01*
X782230D01*
G01X785340Y1320410D02*
Y1322090D01*
X789003Y1325753D01*
X794699D01*
X843538Y1374592D01*
Y1509785D01*
X857277Y1523524D01*
Y1555166D01*
X857276Y1555167D01*
Y1557217D01*
X857277Y1557218D01*
Y1557577D01*
X881165Y1581465D01*
Y1586713D01*
X881765Y1587313D01*
Y1621385D01*
X876378Y1626772D01*
G01X789549Y1322310D02*
X789558Y1322319D01*
X795005D01*
X846013Y1373327D01*
Y1508759D01*
X859752Y1522498D01*
Y1556192D01*
X883640Y1580080D01*
Y1625022D01*
X876378Y1632284D01*
G01X834813Y1528889D02*
X834535D01*
X826900Y1521254D01*
Y1382240D01*
X776138Y1331478D01*
Y1323561D01*
X777009Y1322690D01*
G01X869292Y1644882D02*
X866855Y1642445D01*
Y1587577D01*
X866856Y1587576D01*
Y1586024D01*
X866855Y1586023D01*
Y1584927D01*
X839950Y1558022D01*
Y1525984D01*
X833400Y1519434D01*
Y1381121D01*
X781290Y1329011D01*
Y1328490D01*
G01X876378Y1618111D02*
X877489D01*
X879400Y1616200D01*
Y1587972D01*
X878427Y1586999D01*
Y1582784D01*
X845688Y1550045D01*
Y1515808D01*
X840800Y1510920D01*
Y1379354D01*
X790290Y1328844D01*
Y1328410D01*
G01X876378Y1612599D02*
X872605Y1608826D01*
Y1581206D01*
X842688Y1551289D01*
Y1517051D01*
X837800Y1512163D01*
Y1381109D01*
X785640Y1328949D01*
Y1328370D01*
G01X941274Y900845D02*
X934868D01*
X930343Y896320D01*
X882333D01*
G01X892966Y1508549D02*
Y1499534D01*
X898900Y1493600D01*
Y1426472D01*
X879875Y1407447D01*
Y1383205D01*
X873700Y1377030D01*
Y1375746D01*
G01X893036Y1512600D02*
X890200Y1509764D01*
Y1498700D01*
X896425Y1492475D01*
Y1427498D01*
X877400Y1408473D01*
Y1384231D01*
X873570Y1380401D01*
G01X897638Y1650788D02*
X897008D01*
X892980Y1646760D01*
Y1570170D01*
X890420Y1567610D01*
Y1562660D01*
X902100Y1550980D01*
Y1493601D01*
X913862Y1481839D01*
Y1382438D01*
X920888Y1375412D01*
X983592D01*
X1009390Y1401210D01*
X1032810D01*
X1049100Y1417500D01*
X1133342D01*
X1146375Y1404467D01*
Y1307327D01*
X1149166Y1304536D01*
Y1234030D01*
X1149823Y1233373D01*
G01X897638Y1636614D02*
X896684D01*
X894940Y1634870D01*
Y1568450D01*
X893020Y1566530D01*
G01X920810Y902210D02*
X919565Y903455D01*
Y946665D01*
X936000Y963100D01*
X950060D01*
X953013Y960147D01*
G01X928100Y900650D02*
Y906393D01*
X922132Y912361D01*
Y945632D01*
X936800Y960300D01*
X944024D01*
X947174Y957150D01*
G01X951200Y1030700D02*
X952400Y1029500D01*
Y986463D01*
X940281Y974344D01*
X934142D01*
G01X939481Y980230D02*
X942666D01*
X949925Y987489D01*
Y1027475D01*
X946700Y1030700D01*
G01X987734Y979575D02*
X986697Y978538D01*
X948388D01*
X940904Y971054D01*
X935623D01*
G01D02*
X932482D01*
X931800Y971736D01*
Y977700D01*
X943900Y989800D01*
Y1011340D01*
X946050Y1013490D01*
Y1019130D01*
X936378Y1028802D01*
Y1035722D01*
G01X911811Y1640945D02*
X924246Y1628510D01*
Y1569888D01*
X911188Y1556830D01*
Y1541549D01*
X910333Y1540694D01*
Y1496470D01*
X920362Y1486441D01*
Y1404859D01*
X943309Y1381912D01*
X980896D01*
X1015109Y1416125D01*
X1033000D01*
G01X911811Y1636614D02*
X922621Y1625804D01*
Y1571366D01*
X909563Y1558308D01*
Y1542223D01*
X908708Y1541368D01*
Y1495796D01*
X918737Y1485767D01*
Y1404185D01*
X942635Y1380287D01*
X981570D01*
X1014876Y1413593D01*
X1040093D01*
X1045625Y1419125D01*
X1134369D01*
X1148000Y1405494D01*
Y1308001D01*
X1151761Y1304240D01*
Y1231141D01*
X1150420Y1229800D01*
G01X911811Y1650788D02*
X929777Y1632822D01*
Y1568522D01*
X918438Y1557183D01*
Y1541902D01*
X916267Y1539731D01*
Y1497433D01*
X925237Y1488463D01*
Y1404582D01*
X944657Y1385162D01*
X977271D01*
X1016109Y1424000D01*
X1137450D01*
X1152936Y1408514D01*
Y1329064D01*
X1154500Y1327500D01*
G01X911811Y1646457D02*
X927603Y1630665D01*
Y1568647D01*
X916813Y1557857D01*
Y1542576D01*
X914642Y1540405D01*
Y1496759D01*
X923612Y1487789D01*
Y1403908D01*
X943983Y1383537D01*
X977945D01*
X1016783Y1422375D01*
X1136423D01*
X1150911Y1407887D01*
Y1329500D01*
G01X911811Y1632284D02*
X920537Y1623558D01*
Y1571581D01*
X907938Y1558982D01*
Y1542897D01*
X907083Y1542042D01*
Y1494317D01*
X917112Y1484288D01*
Y1403188D01*
X941638Y1378662D01*
X982244D01*
X1014582Y1411000D01*
X1028000D01*
G01X911811Y1626772D02*
X918662Y1619921D01*
Y1572005D01*
X904062Y1557405D01*
Y1493938D01*
X915487Y1482513D01*
Y1383112D01*
X921562Y1377037D01*
X982918D01*
X1013881Y1408000D01*
X1031500D01*
G01X904725Y1612205D02*
X902100Y1609580D01*
Y1591985D01*
X911710Y1582375D01*
G01X904725Y1607874D02*
X907993Y1604606D01*
Y1592730D01*
X911094Y1589629D01*
Y1585923D01*
G01X1007849Y1033743D02*
X1004506Y1030400D01*
X995500D01*
X991475Y1034425D01*
X954225D01*
X951200Y1031400D01*
Y1030700D01*
G01X946700D02*
X952900Y1036900D01*
X993443D01*
X996600Y1033743D01*
G01X1083355Y1125903D02*
X1080952Y1123500D01*
X1068000D01*
X1062034Y1129466D01*
X1026900D01*
G01X1022400Y1129183D02*
Y1130343D01*
X1025523Y1133466D01*
X1062592D01*
X1070155Y1125903D01*
G01X1119500Y1125100D02*
X1115900Y1121500D01*
X1110500D01*
X1104262Y1127738D01*
X1085190D01*
X1083355Y1125903D01*
G01X1070155D02*
X1074465Y1130213D01*
X1109887D01*
X1115000Y1125100D01*
G01X1105315Y12599D02*
X1109016Y16300D01*
X1118100D01*
X1123700Y10700D01*
X1178007D01*
X1239907Y72600D01*
X1319200D01*
X1328295Y63505D01*
Y55800D01*
G01X1525787Y110827D02*
X1525673D01*
X1521523Y114977D01*
Y126051D01*
X1521000Y126574D01*
Y129600D01*
X1497600Y153000D01*
X1422222D01*
X1412722Y162500D01*
X1395125D01*
X1394735Y162110D01*
X1347561D01*
X1324207Y138756D01*
G01X1525787Y116339D02*
X1523475Y118651D01*
Y130626D01*
X1498626Y155475D01*
X1423248D01*
X1410547Y168176D01*
X1397300D01*
X1393709Y164585D01*
X1341784D01*
X1315102Y137903D01*
G54D12*
X314439Y133669D03*
X323813Y133722D03*
X343962Y181161D03*
X422373Y1359747D03*
X418922Y1356522D03*
X468472Y182441D03*
X539584Y184694D03*
X542155Y187543D03*
X553279Y513331D03*
X536000Y1359826D03*
X541362D03*
X566271Y167387D03*
X598236Y181981D03*
X580279Y512831D03*
X607929Y112329D03*
X663449Y115606D03*
X716600Y181161D03*
X767405Y210364D03*
X763188Y172500D03*
X782230Y1323670D03*
X769728Y1325747D03*
X785340Y1320410D03*
X789549Y1322310D03*
X777009Y1322690D03*
X781290Y1328490D03*
X772900Y1328550D03*
X790290Y1328410D03*
X785640Y1328370D03*
X846400Y473900D03*
X834813Y1528889D03*
X872796Y251714D03*
X890982Y349498D03*
X874800Y355798D03*
X875132Y399200D03*
X878732D03*
Y395600D03*
X875132D03*
X878732Y392000D03*
X875132D03*
X880932Y406400D03*
Y402800D03*
X877332Y406400D03*
Y402800D03*
X880932Y410000D03*
X877332D03*
X857300Y454300D03*
X878500Y476000D03*
X882333Y896320D03*
X863800Y1309876D03*
X872164Y1350464D03*
X873259Y1365805D03*
X872181Y1354764D03*
X873918Y1411149D03*
X873700Y1375746D03*
X873570Y1380401D03*
X892966Y1508549D03*
X893036Y1512600D03*
X893020Y1566530D03*
X889300Y1551000D03*
X922687Y93D03*
X928138Y-8453D03*
X920810Y902210D03*
X928100Y900650D03*
X941274Y900845D03*
X934142Y974344D03*
X939481Y980230D03*
X935623Y971054D03*
X936378Y1035722D03*
X936959Y1360143D03*
X922500Y1509700D03*
X911710Y1582375D03*
X911094Y1585923D03*
X991713Y-115413D03*
X953013Y960147D03*
X947174Y957150D03*
X987734Y979575D03*
X951200Y1030700D03*
X946700D03*
X951525Y1369107D03*
X1010650Y49950D03*
Y67650D03*
X1007849Y1033743D03*
X996600D03*
X1026900Y1129466D03*
X1022400Y1129183D03*
X1033000Y1416125D03*
X1028000Y1411000D03*
X1031500Y1408000D03*
X1079455Y-30742D03*
X1078100Y392600D03*
Y397600D03*
Y402600D03*
X1072600Y392500D03*
Y397500D03*
Y402500D03*
Y407500D03*
X1078100Y407600D03*
X1083355Y1125903D03*
X1070155D03*
X1083355Y1116103D03*
X1070155D03*
X1106300Y-94800D03*
X1101246Y-31005D03*
X1111254Y-31020D03*
X1105328Y-31005D03*
X1119500Y1125100D03*
X1115000D03*
X1134100Y1433300D03*
X1150420Y1229800D03*
X1149823Y1233373D03*
X1154500Y1327500D03*
X1150911Y1329500D03*
X1328295Y55800D03*
X1324207Y138756D03*
X1315102Y137903D03*
X1358971Y129978D03*
X1362685Y130109D03*
X1373553Y700994D03*
X1384475Y255839D03*
X1436204Y159247D03*
X1447700Y579600D03*
X1474700Y579100D03*
X1436213Y615417D03*
X1458713Y652217D03*
X1499775Y248061D03*
X1491594Y508098D03*
X1560425Y162661D03*
X1746400Y244561D03*
X1748100Y1153673D03*
X1808850Y162661D03*
Y615417D03*
X1766721Y720500D03*
X1805250Y1067973D03*
X1891676Y917759D03*
X1884500Y912500D03*
X1904000Y933500D03*
Y929000D03*
Y925000D03*
X1906500Y893400D03*
G54D13*
X450984Y114764D03*
X458071Y96654D03*
X436811Y100591D03*
X450984D03*
X479331Y114764D03*
Y100591D03*
X465157Y120276D03*
X479331D03*
X550197Y114764D03*
Y106103D03*
X536024D03*
X550197Y100591D03*
X536024D03*
X543110Y102166D03*
X550197Y120276D03*
X876378Y1612599D03*
Y1618111D03*
Y1626772D03*
X848032D03*
X876378Y1632284D03*
X848032D03*
X869292Y1644882D03*
X855118D03*
X869292Y1650394D03*
X855118D03*
X904725Y1607874D03*
Y1612205D03*
X911811Y1632284D03*
Y1636614D03*
Y1640945D03*
Y1646457D03*
Y1650788D03*
Y1626772D03*
X897638Y1636614D03*
Y1650788D03*
X1095420Y988592D03*
X1100932D03*
X1123766D03*
X1129278D03*
X1099357Y995678D03*
X1104869D03*
X1127703D03*
X1133215D03*
X1095420Y1002765D03*
X1100932D03*
X1123766D03*
X1129278D03*
X1099357Y1009852D03*
X1104869D03*
X1127703D03*
X1133215D03*
X1095420Y1016938D03*
X1100932D03*
X1123766D03*
X1129278D03*
X1099357Y1024025D03*
X1104869D03*
X1127703D03*
X1133215D03*
X1095420Y1031111D03*
X1100932D03*
X1123766D03*
X1129278D03*
X1099357Y1038198D03*
X1104869D03*
X1127703D03*
X1133215D03*
X1095420Y1160257D03*
X1100932D03*
X1123766D03*
X1129278D03*
X1099357Y1167343D03*
X1104869D03*
X1127703D03*
X1133215D03*
X1123766Y1202776D03*
Y1216949D03*
X1129278Y1202776D03*
Y1216949D03*
X1127703Y1209863D03*
Y1224036D03*
X1133215Y1209863D03*
Y1224036D03*
X1123766Y1231123D03*
X1129278D03*
X1127703Y1238209D03*
X1133215D03*
X1123766Y1287816D03*
Y1301989D03*
Y1316162D03*
X1129278Y1287816D03*
Y1301989D03*
Y1316162D03*
X1127703Y1294902D03*
Y1309075D03*
Y1323249D03*
X1133215Y1294902D03*
Y1309075D03*
Y1323249D03*
X1123766Y1372855D03*
X1129278D03*
X1123766Y1387028D03*
Y1401201D03*
X1129278Y1387028D03*
Y1401201D03*
X1127703Y1379942D03*
Y1394115D03*
Y1408288D03*
X1133215Y1379942D03*
Y1394115D03*
Y1408288D03*
X1447835Y114764D03*
Y120276D03*
X1504528Y114764D03*
X1511614Y116339D03*
Y110827D03*
X1504528Y120276D03*
X1525787Y116339D03*
Y110827D03*
G54D14*
X929331Y48032D03*
X937205Y44095D03*
X929331Y339371D03*
X937205Y335434D03*
X929331Y395669D03*
X937205Y399606D03*
X929331Y498031D03*
Y482283D03*
Y466535D03*
X937205Y494094D03*
Y478346D03*
Y462598D03*
X929331Y513779D03*
X937205Y509842D03*
X929331Y592519D03*
X937205Y588582D03*
X929331Y639763D03*
Y624015D03*
Y608267D03*
X937205Y635826D03*
Y620078D03*
Y604330D03*
X954921Y395669D03*
X947047Y399606D03*
Y391732D03*
Y454724D03*
X954921Y490157D03*
Y474409D03*
Y458661D03*
X947047Y501968D03*
Y486220D03*
Y470472D03*
X954921Y505905D03*
Y600393D03*
X947047Y596456D03*
X954921Y647637D03*
Y631889D03*
Y616141D03*
X947047Y643700D03*
Y627952D03*
Y612204D03*
X1105315Y12599D03*
X1097441Y48032D03*
X1105315Y44095D03*
X1123031Y142520D03*
X1115157Y138583D03*
X1097441Y339371D03*
X1105315Y335434D03*
X1123031Y395669D03*
X1097441D03*
X1115157Y399606D03*
Y391732D03*
X1105315Y399606D03*
G54D15*
X1039845Y1467746D03*
X1026345D03*
X1030845D03*
X1035345D03*
X1039845Y1463246D03*
X1026345D03*
X1030845D03*
X1035345D03*
X1005400Y1463157D03*
X1000900D03*
X996400D03*
X1009900D03*
X1005400Y1467657D03*
X1000900D03*
X996400D03*
X1009900D03*
X1035345Y1476746D03*
X1030845D03*
X1026345D03*
X1039845D03*
Y1472246D03*
X1026345D03*
X1030845D03*
X1035345D03*
X1005400Y1472157D03*
X1000900D03*
X996400D03*
X1009900D03*
Y1476657D03*
X1005400D03*
X1000900D03*
X996400D03*
X1023583Y1489593D03*
X995783D03*
X1000500Y1511400D03*
X1036578Y1511210D03*
X1014690Y1511178D03*
X1010190D03*
X1005690D03*
X1031790Y1511078D03*
X1027290D03*
X1019600Y1511100D03*
X1023583Y1501593D03*
Y1507593D03*
Y1495593D03*
X995783D03*
Y1501593D03*
Y1507593D03*
X1040583Y1517883D03*
X1031799Y1534392D03*
X1031882Y1528985D03*
X1026459Y1528919D03*
X1026376Y1534326D03*
X1014867D03*
X1014950Y1528919D03*
X1020290Y1534392D03*
X1020373Y1528985D03*
X1040500Y1529290D03*
X1040583Y1523883D03*
X1062700Y1463100D03*
X1058200D03*
X1067200D03*
X1062700Y1467600D03*
X1058200D03*
X1067200D03*
X1053700Y1463100D03*
Y1467600D03*
X1062700Y1472100D03*
X1058200D03*
X1067200D03*
Y1476600D03*
X1058200D03*
X1062700D03*
X1053700Y1472100D03*
Y1476600D03*
X1078683Y1489593D03*
X1051383D03*
X1041810Y1511084D03*
X1055310D03*
X1059810D03*
X1064310D03*
X1068810D03*
X1073310D03*
X1078683Y1495593D03*
Y1501593D03*
Y1507593D03*
Y1516593D03*
X1051383Y1495593D03*
Y1501593D03*
Y1507593D03*
X1078683Y1522593D03*
G54D16*
X1101457Y1601181D03*
X1119685D03*
X1108150D03*
X1126378D03*
G54D17*
G01X1134100Y1433300D02*
X1127538Y1426738D01*
X1014974D01*
X976136Y1387900D01*
X946216D01*
X929600Y1404516D01*
Y1502600D01*
X922500Y1509700D01*
G01X1106300Y-94800D02*
X1105500Y-94000D01*
X1026954D01*
X1005541Y-115413D01*
X991713D01*
G01X1511614Y116339D02*
X1514450Y119175D01*
Y132050D01*
X1496238Y150262D01*
X1420660D01*
X1411522Y159400D01*
X1395898D01*
X1395870Y159372D01*
X1388365D01*
X1358971Y129978D01*
G01X1511614Y110827D02*
X1508200Y114241D01*
Y126200D01*
X1486138Y148262D01*
X1410157D01*
X1408802Y146907D01*
X1379483D01*
X1362685Y130109D01*
G54D18*
G01X1133215Y1238209D02*
X1131618D01*
G03X1131118Y1237709I0J-500D01*
G01Y1235964D01*
G02X1129170Y1234016I-1948J0D01*
G01X1065992D01*
X986306Y1189700D01*
X967145Y1179043D01*
X909662Y1147075D01*
X795490Y913255D01*
X754871Y724275D01*
X768881Y663056D01*
X757408Y608414D01*
X675893Y495739D01*
X291948Y240941D01*
X131239Y187342D01*
X128388D01*
G03X127988Y186942I0J-400D01*
G01Y185742D01*
G01X1127703Y1238209D02*
X1129318D01*
G02X1129818Y1237709I0J-500D01*
G01Y1235964D01*
G02X1129170Y1235316I-648J0D01*
G01X1065654D01*
X1056927Y1230463D01*
X1055771Y1230793D01*
X1054722Y1230209D01*
X1054392Y1229053D01*
X1053344Y1228470D01*
X1052188Y1228800D01*
X1051139Y1228217D01*
X1050809Y1227061D01*
X1049760Y1226478D01*
X1048604Y1226807D01*
X1047556Y1226224D01*
X1047226Y1225068D01*
X1024238Y1212284D01*
X1004955Y1201560D01*
X1000134Y1198879D01*
X985674Y1190837D01*
X947352Y1169524D01*
X908673Y1148013D01*
X794252Y913683D01*
X753539Y724266D01*
X767550Y663044D01*
X756192Y608952D01*
X674977Y496693D01*
X291373Y242120D01*
X211200Y215381D01*
Y215382D01*
X131027Y188642D01*
X128388D01*
G02X127988Y189042I0J400D01*
G01Y190242D01*
G01Y638498D02*
Y639698D01*
G02X128388Y640098I400J0D01*
G01X132857D01*
X143799Y646292D01*
X248611Y810816D01*
X364693Y884849D01*
X565504Y925041D01*
X791066Y1051627D01*
X891216Y1205613D01*
X1054021Y1314406D01*
X1066740Y1319056D01*
X1129170D01*
G03X1131118Y1321004I0J1948D01*
G01Y1322749D01*
G02X1131618Y1323249I500J0D01*
G01X1133215D01*
G01X1127703D02*
X1129318D01*
G02X1129818Y1322749I0J-500D01*
G01Y1321004D01*
G02X1129170Y1320356I-648J0D01*
G01X1066509D01*
X1053428Y1315574D01*
X1048711Y1312422D01*
X1047532Y1312656D01*
X1046534Y1311990D01*
X1046300Y1310811D01*
X1045302Y1310144D01*
X1044123Y1310378D01*
X1043125Y1309712D01*
X1042891Y1308533D01*
X1041893Y1307866D01*
X1040714Y1308100D01*
X1039717Y1307434D01*
X1039482Y1306255D01*
X890272Y1206546D01*
X790150Y1052605D01*
X565047Y926276D01*
X364199Y886076D01*
X247669Y811758D01*
X142876Y647264D01*
X132514Y641398D01*
X128388D01*
G02X127988Y641798I0J400D01*
G01Y642998D01*
G01Y1091254D02*
Y1092454D01*
G02X128388Y1092854I400J0D01*
G01X130778D01*
X132132Y1093154D01*
X136869Y1096170D01*
X141657Y1099219D01*
X155628Y1121147D01*
X173278Y1132392D01*
X867039Y1286175D01*
X1030055Y1390584D01*
X1037156Y1393181D01*
X1039523Y1394047D01*
X1049442Y1397674D01*
Y1397675D01*
X1066995Y1404095D01*
X1128683D01*
G03X1131118Y1406530I0J2435D01*
G01Y1407788D01*
G02X1131618Y1408288I500J0D01*
G01X1133215D01*
G01X1127703D02*
X1129318D01*
G02X1129818Y1407788I0J-500D01*
G01Y1406530D01*
G02X1128683Y1405395I-1135J0D01*
G01X1066764D01*
X1049501Y1399081D01*
X1048410Y1399587D01*
X1047283Y1399175D01*
X1046777Y1398085D01*
X1045650Y1397673D01*
X1044560Y1398179D01*
X1043433Y1397767D01*
X1042926Y1396677D01*
X1041799Y1396264D01*
X1040709Y1396771D01*
X1039582Y1396359D01*
X1039076Y1395268D01*
X1029474Y1391756D01*
X866532Y1287395D01*
X172773Y1133612D01*
X154686Y1122089D01*
X140715Y1100161D01*
X131627Y1094374D01*
Y1094375D01*
X130635Y1094154D01*
X128388D01*
G02X127988Y1094554I0J400D01*
G01Y1095754D01*
G01X1129278Y1231123D02*
X1127681D01*
G03X1127181Y1230623I0J-500D01*
G01Y1228878D01*
G02X1125233Y1226930I-1948J0D01*
G01X1066958D01*
X951093Y1162477D01*
X951092D01*
X932251Y1151996D01*
X913411Y1141516D01*
X800282Y909891D01*
X760484Y724723D01*
X775399Y660596D01*
X763176Y602378D01*
X673118Y477897D01*
X310625Y212357D01*
X256465Y187342D01*
X252600D01*
G03X252200Y186942I0J-400D01*
G01Y185742D01*
G01X1123766Y1231123D02*
X1125381D01*
G02X1125881Y1230623I0J-500D01*
G01Y1228878D01*
G02X1125233Y1228230I-648J0D01*
G01X1066620D01*
X1059668Y1224363D01*
X1058512Y1224692D01*
X1057463Y1224109D01*
X1057133Y1222953D01*
X1056085Y1222370D01*
X1054929Y1222699D01*
X1053880Y1222116D01*
X1053550Y1220960D01*
X1052502Y1220377D01*
X1051346Y1220706D01*
X1050297Y1220123D01*
X1049967Y1218967D01*
X988145Y1184577D01*
X950461Y1163614D01*
X912422Y1142454D01*
X799044Y910319D01*
X759151Y724712D01*
X774067Y660582D01*
X761960Y602916D01*
X672184Y478825D01*
Y478826D01*
X309962Y213483D01*
X283071Y201063D01*
Y201064D01*
X256179Y188642D01*
X252600D01*
G02X252200Y189042I0J400D01*
G01Y190242D01*
G01Y638498D02*
Y639698D01*
G02X252600Y640098I400J0D01*
G01X256252D01*
X260888Y643051D01*
X271470Y659653D01*
X300885Y789940D01*
X350237Y867413D01*
X359033Y873025D01*
X367828Y878636D01*
X568604Y918825D01*
X792832Y1044663D01*
X894292Y1200894D01*
X1054300Y1307818D01*
X1065654Y1311969D01*
X1125233D01*
G03X1127181Y1313917I0J1948D01*
G01Y1315662D01*
G02X1127681Y1316162I500J0D01*
G01X1129278D01*
G01X1123766D02*
X1125381D01*
G02X1125881Y1315662I0J-500D01*
G01Y1313917D01*
G02X1125233Y1313269I-648J0D01*
G01X1065423D01*
X1053707Y1308986D01*
X1050187Y1306634D01*
X1049008Y1306868D01*
X1048010Y1306201D01*
X1047775Y1305022D01*
X1046778Y1304356D01*
X1045599Y1304590D01*
X1044601Y1303923D01*
X1044366Y1302744D01*
X1043369Y1302078D01*
X1042190Y1302312D01*
X1041192Y1301645D01*
X1040957Y1300466D01*
X893347Y1201827D01*
X791916Y1045640D01*
X568147Y920060D01*
X367334Y879863D01*
X349294Y868355D01*
X336802Y848743D01*
X299666Y790448D01*
X270251Y660161D01*
X259946Y643993D01*
X255872Y641398D01*
X252600D01*
G02X252200Y641798I0J400D01*
G01Y642998D01*
G01Y1091254D02*
Y1092454D01*
G02X252600Y1092854I400J0D01*
G01X256601D01*
X291274Y1100226D01*
X414239Y1180082D01*
X869865Y1281088D01*
X1029124Y1382548D01*
X1068658Y1397007D01*
X1068659Y1397008D01*
X1125233D01*
G03X1127181Y1398956I0J1948D01*
G01Y1400701D01*
G02X1127681Y1401201I500J0D01*
G01X1129278D01*
G01X1123766D02*
X1125381D01*
G02X1125881Y1400701I0J-500D01*
G01Y1398956D01*
G02X1125233Y1398308I-648J0D01*
G01X1068428D01*
X1053974Y1393022D01*
X1052883Y1393528D01*
X1051756Y1393116D01*
X1051250Y1392026D01*
X1050123Y1391613D01*
X1049033Y1392120D01*
X1047906Y1391707D01*
X1047399Y1390617D01*
X1046273Y1390205D01*
X1045182Y1390711D01*
X1044055Y1390299D01*
X1043549Y1389209D01*
X1028544Y1383721D01*
X869360Y1282308D01*
X413728Y1181301D01*
X290768Y1101448D01*
X273616Y1097801D01*
Y1097802D01*
X256464Y1094154D01*
X252600D01*
G02X252200Y1094554I0J400D01*
G01Y1095754D01*
G01X1133215Y1224036D02*
X1131618D01*
G03X1131118Y1223536I0J-500D01*
G01Y1221791D01*
G02X1129170Y1219843I-1948J0D01*
G01X1066670D01*
X984558Y1174164D01*
X979663Y1171441D01*
X965194Y1163392D01*
X916898Y1136526D01*
X877304Y1055459D01*
X818163Y820645D01*
X839753Y726955D01*
X794666Y551200D01*
X465294Y313843D01*
X384677Y189716D01*
X380485Y187342D01*
X376813D01*
G03X376413Y186942I0J-400D01*
G01Y185742D01*
G01X1127703Y1224036D02*
X1129318D01*
G02X1129818Y1223536I0J-500D01*
G01Y1221791D01*
G02X1129170Y1221143I-648J0D01*
G01X1066332D01*
X1061285Y1218336D01*
X1060129Y1218665D01*
X1059081Y1218082D01*
X1058751Y1216926D01*
X1057702Y1216342D01*
X1056546Y1216672D01*
X1055498Y1216089D01*
X1055168Y1214933D01*
X1054119Y1214349D01*
X1052963Y1214679D01*
X1051915Y1214095D01*
X1051585Y1212939D01*
X915909Y1137464D01*
X876076Y1055908D01*
X816825Y820659D01*
X838415Y726971D01*
X793523Y551980D01*
X628931Y433368D01*
X464336Y314756D01*
X383760Y190691D01*
X380142Y188642D01*
X376813D01*
G02X376413Y189042I0J400D01*
G01Y190242D01*
G01X1133215Y1309075D02*
X1131618D01*
G03X1131118Y1308575I0J-500D01*
G01Y1306830D01*
G02X1129170Y1304882I-1948J0D01*
G01X1066421D01*
X1055975Y1301063D01*
X974401Y1246552D01*
X902923Y1198787D01*
X798138Y1037433D01*
X575853Y912688D01*
X573861Y911485D01*
X485242Y892765D01*
X441391Y855806D01*
X409413Y711147D01*
X398525Y661894D01*
X386306Y642654D01*
X383296Y640737D01*
X380419Y640098D01*
X376813D01*
G03X376413Y639698I0J-400D01*
G01Y638498D01*
G01X1127703Y1309075D02*
X1129318D01*
G02X1129818Y1308575I0J-500D01*
G01Y1306830D01*
G02X1129170Y1306182I-648J0D01*
G01X1066190D01*
X1055382Y1302231D01*
X1054384Y1301564D01*
X1053205Y1301799D01*
X1052208Y1301132D01*
X1051973Y1299953D01*
X1050975Y1299286D01*
X1049796Y1299521D01*
X1048799Y1298854D01*
X1048564Y1297675D01*
X1047566Y1297008D01*
X1046387Y1297243D01*
X1045390Y1296576D01*
X1045155Y1295397D01*
X901978Y1199720D01*
X797222Y1038410D01*
X575198Y913812D01*
X573377Y912712D01*
X484653Y893970D01*
X440216Y856517D01*
X408143Y711428D01*
X397305Y662398D01*
X385363Y643596D01*
X382791Y641957D01*
X380276Y641398D01*
X376813D01*
G02X376413Y641798I0J400D01*
G01Y642998D01*
G01Y1091254D02*
Y1092454D01*
G02X376813Y1092854I400J0D01*
G01X431296D01*
X464969Y1100318D01*
X665837Y1228288D01*
X767875Y1250910D01*
Y1250911D01*
X870362Y1273634D01*
X1032345Y1376833D01*
X1068131Y1389922D01*
X1129170D01*
G03X1131118Y1391870I0J1948D01*
G01Y1393615D01*
G02X1131618Y1394115I500J0D01*
G01X1133215D01*
G01X376413Y1095754D02*
Y1094554D01*
G03X376813Y1094154I400J0D01*
G01X431153D01*
X464464Y1101538D01*
X665332Y1229508D01*
X869857Y1274854D01*
X1031765Y1378006D01*
X1047601Y1383798D01*
X1048107Y1384888D01*
X1049234Y1385300D01*
X1050324Y1384794D01*
X1051451Y1385206D01*
X1051957Y1386296D01*
X1053084Y1386709D01*
X1054175Y1386202D01*
X1055302Y1386614D01*
X1055808Y1387705D01*
X1056935Y1388117D01*
X1058025Y1387610D01*
X1067900Y1391222D01*
X1129170D01*
G03X1129818Y1391870I0J648D01*
G01Y1393615D01*
G03X1129318Y1394115I-500J0D01*
G01X1127703D01*
G01X500625Y185742D02*
Y186942D01*
G02X501025Y187342I400J0D01*
G01X503736D01*
X506001Y188721D01*
X536872Y238663D01*
X614847Y289302D01*
X705801Y411675D01*
X796771Y534070D01*
X846554Y732786D01*
X826292Y814875D01*
X857698Y940193D01*
X889103Y1065511D01*
X921720Y1132298D01*
X1066340Y1212756D01*
X1125233D01*
G03X1127181Y1214704I0J1948D01*
G01Y1216449D01*
G02X1127681Y1216949I500J0D01*
G01X1129278D01*
G01X1123766D02*
X1125381D01*
G02X1125881Y1216449I0J-500D01*
G01Y1214704D01*
G02X1125233Y1214056I-648J0D01*
G01X1066002D01*
X1061339Y1211462D01*
X1060183Y1211791D01*
X1059134Y1211208D01*
X1058805Y1210052D01*
X1057756Y1209468D01*
X1056600Y1209798D01*
X1055551Y1209215D01*
X1055222Y1208059D01*
X1054173Y1207475D01*
X1053017Y1207805D01*
X1051969Y1207221D01*
X1051639Y1206065D01*
X920730Y1133236D01*
X887875Y1065959D01*
X824952Y814877D01*
X845214Y732788D01*
X795572Y534638D01*
X613942Y290266D01*
X535919Y239595D01*
X505058Y189670D01*
X503371Y188642D01*
X501025D01*
G02X500625Y189042I0J400D01*
G01Y190242D01*
G01Y638498D02*
Y639698D01*
G02X501025Y640098I400J0D01*
G01X504565D01*
X506088Y640435D01*
X509474Y642592D01*
X532982Y679482D01*
X560915Y805467D01*
X627375Y909793D01*
X649528Y944570D01*
X725789Y987368D01*
X802049Y1030165D01*
X908389Y1193910D01*
X1058809Y1294428D01*
X1068021Y1297796D01*
X1125233D01*
G03X1127181Y1299744I0J1948D01*
G01Y1301489D01*
G02X1127681Y1301989I500J0D01*
G01X1129278D01*
G01X1123766D02*
X1125381D01*
G02X1125881Y1301489I0J-500D01*
G01Y1299744D01*
G02X1125233Y1299096I-648J0D01*
G01X1067790D01*
X1058216Y1295596D01*
X1055769Y1293961D01*
X1054590Y1294195D01*
X1053592Y1293528D01*
X1053358Y1292349D01*
X1052360Y1291683D01*
X1051181Y1291917D01*
X1050183Y1291250D01*
X1049949Y1290071D01*
X1048951Y1289405D01*
X1047772Y1289639D01*
X1046774Y1288972D01*
X1046540Y1287793D01*
X907444Y1194843D01*
X854289Y1112993D01*
X801133Y1031142D01*
X648607Y945544D01*
X559695Y805972D01*
X531762Y679987D01*
X508532Y643534D01*
X505583Y641655D01*
Y641656D01*
X504422Y641398D01*
X501025D01*
G02X500625Y641798I0J400D01*
G01Y642998D01*
G01Y1091254D02*
Y1092454D01*
G02X501025Y1092854I400J0D01*
G01X513711D01*
X532740Y1097074D01*
X762556Y1243496D01*
X874294Y1268270D01*
X1037803Y1372433D01*
X1066245Y1382835D01*
X1125233D01*
G03X1127181Y1384783I0J1948D01*
G01Y1386528D01*
G02X1127681Y1387028I500J0D01*
G01X1129278D01*
G01X1123766D02*
X1125381D01*
G02X1125881Y1386528I0J-500D01*
G01Y1384783D01*
G02X1125233Y1384135I-648J0D01*
G01X1066014D01*
X1060923Y1382273D01*
X1059833Y1382780D01*
X1058706Y1382367D01*
X1058200Y1381277D01*
X1057073Y1380865D01*
X1055982Y1381371D01*
X1054855Y1380959D01*
X1054349Y1379869D01*
X1053222Y1379457D01*
X1052132Y1379963D01*
X1051005Y1379551D01*
X1050498Y1378461D01*
X1037223Y1373606D01*
X873789Y1269490D01*
X762051Y1244716D01*
X532235Y1098294D01*
X513568Y1094154D01*
X501025D01*
G02X500625Y1094554I0J400D01*
G01Y1095754D01*
G01X1133215Y1209863D02*
X1131618D01*
G03X1131118Y1209363I0J-500D01*
G01Y1207618D01*
G02X1129170Y1205670I-1948J0D01*
G01X1080706D01*
X922673Y1117744D01*
X899274Y1069827D01*
X867028Y941150D01*
X834779Y812473D01*
X852878Y739149D01*
X758206Y361285D01*
X634165Y189829D01*
X629773Y187342D01*
X625238D01*
G03X624838Y186942I0J-400D01*
G01Y185742D01*
G01X1127703Y1209863D02*
X1129318D01*
G02X1129818Y1209363I0J-500D01*
G01Y1207618D01*
G02X1129170Y1206970I-648J0D01*
G01X1080368D01*
X1071548Y1202063D01*
X1070392Y1202392D01*
X1069343Y1201809D01*
X1069013Y1200653D01*
X1067965Y1200069D01*
X1066809Y1200399D01*
X1065760Y1199815D01*
X1065431Y1198659D01*
X1064382Y1198076D01*
X1063226Y1198405D01*
X1062177Y1197822D01*
X1061848Y1196666D01*
X921683Y1118682D01*
X898046Y1070275D01*
X833439Y812475D01*
X851538Y739151D01*
X757005Y361844D01*
X633278Y190821D01*
X629430Y188642D01*
X625238D01*
G02X624838Y189042I0J400D01*
G01Y190242D01*
G01Y638498D02*
Y639698D01*
G02X625163Y640090I399J0D01*
G02X625238Y640098I80J-392D01*
G01X628210D01*
X631336Y640791D01*
X637740Y644868D01*
X770255Y847817D01*
X785232Y916001D01*
X917453Y1187473D01*
X1051180Y1276834D01*
X1089115Y1290709D01*
X1129170D01*
G03X1131118Y1292657I0J1948D01*
G01Y1294402D01*
G02X1131618Y1294902I500J0D01*
G01X1133215D01*
G01X1127703D02*
X1129318D01*
G02X1129818Y1294402I0J-500D01*
G01Y1292657D01*
G02X1129170Y1292009I-648J0D01*
G01X1088884D01*
X1062406Y1282325D01*
X1061316Y1282831D01*
X1060189Y1282419D01*
X1059683Y1281329D01*
X1058556Y1280917D01*
X1057465Y1281423D01*
X1056339Y1281011D01*
X1055832Y1279921D01*
X1054705Y1279508D01*
X1053615Y1280015D01*
X1052488Y1279602D01*
X1051982Y1278512D01*
X1050584Y1278001D01*
Y1278000D01*
X916438Y1188359D01*
X783995Y916431D01*
X769036Y848328D01*
X636805Y645814D01*
X630831Y642011D01*
Y642012D01*
X628067Y641398D01*
X625238D01*
G02X624838Y641798I0J400D01*
G01Y642998D01*
G01Y1091254D02*
Y1092454D01*
G02X625238Y1092854I400J0D01*
G01X627538D01*
X630214Y1093447D01*
X638611Y1098796D01*
X681878Y1166703D01*
X805301Y1245333D01*
X872846Y1260308D01*
X1013836Y1350123D01*
X1083899Y1375749D01*
X1129170D01*
G03X1131118Y1377697I0J1948D01*
G01Y1379442D01*
G02X1131618Y1379942I500J0D01*
G01X1133215D01*
G01X624838Y1095754D02*
Y1094554D01*
G03X625238Y1094154I400J0D01*
G01X627395D01*
X629709Y1094667D01*
X637669Y1099738D01*
X680936Y1167645D01*
X804603Y1246430D01*
X804602D01*
X804796Y1246553D01*
X872341Y1261528D01*
X1013256Y1351296D01*
X1032750Y1358426D01*
X1052110Y1365507D01*
X1052617Y1366597D01*
X1053744Y1367009D01*
X1054834Y1366503D01*
X1055961Y1366915D01*
X1056467Y1368005D01*
X1057594Y1368418D01*
X1058684Y1367911D01*
X1059811Y1368323D01*
X1060318Y1369414D01*
X1061445Y1369826D01*
X1062535Y1369320D01*
X1083668Y1377049D01*
X1129170D01*
G03X1129818Y1377697I0J648D01*
G01Y1379442D01*
G03X1129318Y1379942I-500J0D01*
G01X1127703D01*
G01X1129278Y1202776D02*
X1127681D01*
G03X1127181Y1202276I0J-500D01*
G01Y1200531D01*
G02X1125233Y1198583I-1948J0D01*
G01X1078389D01*
X927529Y1114655D01*
X907840Y1074336D01*
X849306Y840746D01*
X841676Y810303D01*
X841677D01*
X841676Y810302D01*
X849953Y776736D01*
X858307Y742854D01*
X746711Y299702D01*
X765979Y237860D01*
X756582Y191068D01*
X755299Y189137D01*
X752128Y187342D01*
X749451D01*
G03X749051Y186942I0J-400D01*
G01Y185742D01*
G01X1123766Y1202776D02*
X1125381D01*
G02X1125881Y1202276I0J-500D01*
G01Y1200531D01*
G02X1125233Y1199883I-648J0D01*
G01X1078051D01*
X1074510Y1197913D01*
X1073354Y1198243D01*
X1072305Y1197659D01*
X1071976Y1196503D01*
X1070927Y1195920D01*
X1069771Y1196249D01*
X1068722Y1195666D01*
X1068393Y1194510D01*
X1067344Y1193927D01*
X1066188Y1194256D01*
X1065139Y1193673D01*
X1064810Y1192517D01*
X926539Y1115593D01*
X906612Y1074784D01*
X840336Y810305D01*
X856967Y742857D01*
X856966D01*
X745360Y299665D01*
X764638Y237790D01*
X759998Y214682D01*
X755357Y191575D01*
X754388Y190116D01*
X751785Y188642D01*
X749451D01*
G02X749051Y189042I0J400D01*
G01Y190242D01*
G01Y638498D02*
Y639698D01*
G02X749451Y640098I400J0D01*
G01X752127D01*
X754872Y641427D01*
X755824Y644297D01*
X743648Y698782D01*
X789443Y911858D01*
X921539Y1182322D01*
X1053218Y1270316D01*
X1089598Y1283623D01*
X1125233D01*
G03X1127181Y1285571I0J1948D01*
G01Y1287316D01*
G02X1127681Y1287816I500J0D01*
G01X1129278D01*
G01X1123766D02*
X1125381D01*
G02X1125881Y1287316I0J-500D01*
G01Y1285571D01*
G02X1125233Y1284923I-648J0D01*
G01X1089367D01*
X1064177Y1275709D01*
X1063086Y1276215D01*
X1061959Y1275803D01*
X1061453Y1274713D01*
X1060326Y1274301D01*
X1059236Y1274807D01*
X1058109Y1274395D01*
X1057602Y1273305D01*
X1056476Y1272892D01*
X1055385Y1273399D01*
X1054258Y1272986D01*
X1053752Y1271896D01*
X1052625Y1271484D01*
X920524Y1183209D01*
X788205Y912286D01*
X742316Y698776D01*
X754476Y644365D01*
X753810Y642359D01*
X752819Y641879D01*
X752820D01*
X751828Y641398D01*
X749451D01*
G02X749051Y641798I0J400D01*
G01Y642998D01*
G01X1129278Y1372855D02*
X1127681D01*
G03X1127181Y1372355I0J-500D01*
G01Y1370610D01*
G02X1125233Y1368662I-1948J0D01*
G01X1090279D01*
X1012057Y1340050D01*
X866910Y1243058D01*
X761897Y1098298D01*
X753416Y1092854D01*
X749451D01*
G03X749051Y1092454I0J-400D01*
G01Y1091254D01*
G01X1123766Y1372855D02*
X1125381D01*
G02X1125881Y1372355I0J-500D01*
G01Y1370610D01*
G02X1125233Y1369962I-648J0D01*
G01X1090048D01*
X1067219Y1361612D01*
X1066129Y1362118D01*
X1065002Y1361706D01*
X1064495Y1360616D01*
X1063368Y1360203D01*
X1062278Y1360710D01*
X1061151Y1360297D01*
X1060645Y1359207D01*
X1059518Y1358795D01*
X1058428Y1359301D01*
X1057301Y1358889D01*
X1056794Y1357799D01*
X1011464Y1341218D01*
X938760Y1292636D01*
X865994Y1244010D01*
X760988Y1099260D01*
X753034Y1094154D01*
X749451D01*
G02X749051Y1094554I0J400D01*
G01Y1095754D01*
G01X1129278Y1160257D02*
X1127681D01*
G03X1127181Y1159757I0J-500D01*
G01Y1158012D01*
G03X1127317Y1157682I466J-1D01*
G01X1127664Y1157336D01*
X1128018Y1156982D01*
X1131738Y1154249D01*
X1132926Y1154430D01*
X1133893Y1153720D01*
X1134075Y1152532D01*
X1135042Y1151821D01*
X1136230Y1152003D01*
X1137197Y1151292D01*
X1137379Y1150104D01*
X1138346Y1149393D01*
X1139534Y1149575D01*
X1140501Y1148864D01*
X1140682Y1147676D01*
X1180117Y1118699D01*
X1244964Y1032587D01*
X1266921Y935187D01*
X1210867Y656199D01*
X1231076Y561095D01*
X1211246Y462411D01*
X1273300Y187939D01*
Y183223D01*
G03X1273700Y182823I400J0D01*
G01X1274900D01*
G01X1123766Y1160257D02*
X1125381D01*
G02X1125881Y1159757I0J-500D01*
G01Y1158012D01*
G03X1126395Y1156764I1767J-2D01*
G03X1126398Y1156762I962J1440D01*
G01X1127168Y1155992D01*
X1179193Y1117764D01*
X1243757Y1032028D01*
X1265591Y935171D01*
X1251578Y865426D01*
Y865425D01*
X1209539Y656192D01*
X1229748Y561088D01*
X1209916Y462395D01*
X1272000Y187793D01*
Y183223D01*
G02X1271600Y182823I-400J0D01*
G01X1270400D01*
G01X1402713Y185742D02*
Y186942D01*
G03X1402313Y187342I-400J0D01*
G01X1400121D01*
X1398038Y187804D01*
X1393743Y190542D01*
X1390532Y195581D01*
X1373616Y234792D01*
X1318164Y523369D01*
X1363957Y751219D01*
X1319739Y947353D01*
X1268236Y1028131D01*
X1186150Y1134679D01*
X1157853Y1155469D01*
X1156665Y1155287D01*
X1155698Y1155997D01*
X1155516Y1157186D01*
X1154549Y1157896D01*
X1153361Y1157714D01*
X1152394Y1158425D01*
X1152212Y1159613D01*
X1151245Y1160324D01*
X1150057Y1160142D01*
X1149090Y1160853D01*
X1148908Y1162041D01*
X1139100Y1169247D01*
X1136074Y1170236D01*
X1131748D01*
G03X1131100Y1169588I0J-648D01*
G01Y1167843D01*
G03X1131600Y1167343I500J0D01*
G01X1133215D01*
G01X1402713Y190242D02*
Y189042D01*
G02X1402313Y188642I-400J0D01*
G01X1400264D01*
X1398544Y189025D01*
Y189024D01*
X1394685Y191484D01*
X1391685Y196192D01*
X1374866Y235177D01*
X1319489Y523364D01*
X1365288Y751233D01*
X1320958Y947861D01*
X1269301Y1028879D01*
X1187068Y1135618D01*
X1139702Y1170418D01*
X1136282Y1171536D01*
X1131748D01*
G03X1129800Y1169588I0J-1948D01*
G01Y1167843D01*
G02X1129300Y1167343I-500J0D01*
G01X1127703D01*
G01X1095420Y1160257D02*
X1097126D01*
G02X1097526Y1159857I0J-400D01*
G01Y1157580D01*
X1099161Y1155944D01*
X1129461Y1146065D01*
X1134940Y1142040D01*
X1134941D01*
X1136409Y1140961D01*
X1137585Y1140097D01*
X1170888Y1115631D01*
X1228590Y1039008D01*
X1254457Y924273D01*
X1200712Y656810D01*
X1219837Y566793D01*
X1196404Y450202D01*
X1258350Y174823D01*
Y168223D01*
G02X1257950Y167823I-400J0D01*
G01X1256750D01*
G01X1100932Y1160257D02*
X1099226D01*
G03X1098826Y1159857I0J-400D01*
G01Y1158119D01*
X1099861Y1157084D01*
X1113734Y1152561D01*
X1114806Y1153105D01*
X1115947Y1152733D01*
X1116491Y1151662D01*
X1117632Y1151290D01*
X1118704Y1151835D01*
X1119845Y1151463D01*
X1120389Y1150391D01*
X1121530Y1150019D01*
X1122602Y1150564D01*
X1123743Y1150192D01*
X1124288Y1149120D01*
X1130063Y1147237D01*
X1135367Y1143340D01*
X1135368D01*
X1137179Y1142009D01*
X1138355Y1141145D01*
X1171812Y1116566D01*
X1229797Y1039567D01*
X1255787Y924289D01*
X1202040Y656817D01*
X1221165Y566800D01*
X1215281Y537525D01*
X1197734Y450217D01*
X1259650Y174968D01*
Y168223D01*
G03X1260050Y167823I400J0D01*
G01X1261250D01*
G01X1380963D02*
X1382163D01*
G03X1382563Y168223I0J400D01*
G01Y176422D01*
X1382562D01*
X1381219Y179536D01*
X1371823Y201318D01*
X1311434Y523039D01*
X1357080Y750196D01*
X1335161Y847519D01*
X1335160D01*
X1313243Y944840D01*
X1263101Y1023546D01*
X1180805Y1130370D01*
X1138145Y1161711D01*
X1133741Y1163150D01*
X1103420D01*
G02X1101472Y1165098I0J1948D01*
G01Y1166843D01*
G03X1100972Y1167343I-500J0D01*
G01X1099357D01*
G01X1385463Y167823D02*
X1384263D01*
G02X1383863Y168223I0J400D01*
G01Y176691D01*
X1373075Y201700D01*
X1312759Y523031D01*
X1358410Y750211D01*
X1314462Y945347D01*
X1264167Y1024294D01*
X1181723Y1131309D01*
X1166931Y1142176D01*
X1166749Y1143365D01*
X1165782Y1144075D01*
X1164594Y1143893D01*
X1163627Y1144604D01*
X1163445Y1145792D01*
X1162478Y1146503D01*
X1161290Y1146321D01*
X1160323Y1147031D01*
X1160141Y1148220D01*
X1159174Y1148930D01*
X1157986Y1148748D01*
X1138747Y1162882D01*
X1133949Y1164450D01*
X1103420D01*
G02X1102772Y1165098I0J648D01*
G01Y1166843D01*
G02X1103272Y1167343I500J0D01*
G01X1104869D01*
G54D19*
G01X479331Y114764D02*
Y116520D01*
X479832Y117021D01*
X482384D01*
X483767Y118404D01*
X486300Y122230D01*
X508747Y137095D01*
X559235Y147824D01*
X589282Y141438D01*
X659762Y95669D01*
X732635Y75190D01*
X768231Y82756D01*
Y82755D01*
X803333Y90217D01*
X874291Y75134D01*
X920907Y44862D01*
X927072Y43551D01*
X930991D01*
G03X932357Y44117I0J1932D01*
G01X933654Y45414D01*
G02X934347Y45526I424J-424D01*
G01X937205Y44095D01*
G01X479331Y120276D02*
Y118621D01*
X479831Y118121D01*
X481928D01*
X482911Y119104D01*
X485506Y123024D01*
X508314Y138128D01*
X559235Y148949D01*
X589710Y142472D01*
X660221Y96683D01*
X732672Y76323D01*
X803333Y91342D01*
X874719Y76168D01*
X908686Y54111D01*
X909446Y54272D01*
X910704Y53456D01*
X910866Y52695D01*
X912124Y51878D01*
X912885Y52039D01*
X914143Y51223D01*
X914305Y50462D01*
X915563Y49645D01*
X916324Y49807D01*
X917582Y48990D01*
X917743Y48229D01*
X921335Y45896D01*
X927188Y44651D01*
X930990D01*
G03X931579Y44895I0J832D01*
G01X932429Y45745D01*
G03X932299Y46545I-354J353D01*
G01X932260Y46565D01*
X929331Y48032D01*
G01X1099357Y1038198D02*
X1101063D01*
G03X1101563Y1038698I0J500D01*
G01Y1040564D01*
G03X1100723Y1041404I-840J0D01*
G01X1090281D01*
X1087352Y1039422D01*
X1087194Y1038603D01*
X1085952Y1037762D01*
X1085132Y1037920D01*
X1083890Y1037079D01*
X1083732Y1036260D01*
X1082490Y1035419D01*
X1081671Y1035577D01*
X1080428Y1034737D01*
X1080270Y1033917D01*
X1079028Y1033077D01*
X1078209Y1033235D01*
X1060135Y1021004D01*
X1059987Y1020240D01*
X1058745Y1019400D01*
X1057981Y1019547D01*
X1056739Y1018706D01*
X1056592Y1017943D01*
X1055349Y1017102D01*
X1054586Y1017249D01*
X1053343Y1016409D01*
X1053196Y1015645D01*
X1051954Y1014804D01*
X1051190Y1014951D01*
X1049948Y1014111D01*
X1049801Y1013347D01*
X1048558Y1012506D01*
X1047794Y1012654D01*
X1041425Y1008344D01*
X1025140Y997324D01*
Y997323D01*
X1024361Y996041D01*
X1024545Y995286D01*
X1023765Y994004D01*
X1023009Y993820D01*
X1022230Y992538D01*
X1022414Y991783D01*
X1021635Y990501D01*
X1020879Y990317D01*
X1020100Y989035D01*
X1020284Y988280D01*
X1019504Y986998D01*
X1018748Y986814D01*
X1017969Y985532D01*
X1018153Y984777D01*
X1017374Y983495D01*
X1016618Y983311D01*
X1006225Y966223D01*
X1006409Y965468D01*
X1005630Y964186D01*
X1004874Y964002D01*
X1004095Y962720D01*
X1004279Y961965D01*
X1003499Y960683D01*
X1002744Y960499D01*
X1001965Y959217D01*
X1002149Y958462D01*
X1001369Y957180D01*
X1000613Y956996D01*
X859564Y725088D01*
X847387Y677638D01*
X875098Y541555D01*
X924979Y464779D01*
X927653Y463148D01*
X930923D01*
G03X931616Y463435I0J980D01*
G01X932429Y464248D01*
G03X932299Y465048I-354J353D01*
G01X932260Y465068D01*
X929331Y466535D01*
G01X1104869Y1038198D02*
X1103163D01*
G02X1102663Y1038698I0J500D01*
G01Y1040564D01*
G03X1100723Y1042504I-1940J0D01*
G01X1089943D01*
X1040808Y1009256D01*
X1036736Y1006501D01*
X1032665Y1003746D01*
X1024325Y998101D01*
X999909Y957958D01*
X858539Y725520D01*
X846258Y677666D01*
X874061Y541130D01*
X924192Y463969D01*
X925743Y463024D01*
X927344Y462048D01*
X930923D01*
G03X932394Y462657I0J2080D01*
G01X933654Y463917D01*
G02X934347Y464029I424J-424D01*
G01X937205Y462598D01*
G01X1095420Y1031111D02*
X1097126D01*
G03X1097626Y1031611I0J500D01*
G01Y1033477D01*
G03X1096998Y1034105I-628J0D01*
G01X1090340D01*
X1090339Y1034104D01*
X1088701Y1032996D01*
X1088543Y1032177D01*
X1087301Y1031336D01*
X1086482Y1031494D01*
X1085239Y1030654D01*
X1085081Y1029834D01*
X1083839Y1028994D01*
X1083020Y1029152D01*
X1081777Y1028311D01*
X1081619Y1027492D01*
X1080377Y1026651D01*
X1079558Y1026809D01*
X1029155Y992707D01*
X1025932Y987408D01*
X1026116Y986652D01*
X1025336Y985371D01*
X1024581Y985187D01*
X1023801Y983905D01*
X1023985Y983149D01*
X1023206Y981868D01*
X1022450Y981684D01*
X1021670Y980402D01*
X1021854Y979646D01*
X1021075Y978365D01*
X1020319Y978181D01*
X1007795Y957591D01*
X1007979Y956835D01*
X1007199Y955553D01*
X1006444Y955369D01*
X1005664Y954088D01*
X1005848Y953332D01*
X1005069Y952051D01*
X1004313Y951867D01*
X1003533Y950585D01*
X1003717Y949829D01*
X1002938Y948548D01*
X1002182Y948364D01*
X1001403Y947082D01*
X1001587Y946326D01*
X1000807Y945045D01*
X1000051Y944861D01*
X979862Y911670D01*
X980046Y910915D01*
X979267Y909633D01*
X978511Y909449D01*
X977731Y908167D01*
X977915Y907412D01*
X977136Y906130D01*
X976380Y905946D01*
X975601Y904665D01*
X975785Y903909D01*
X975005Y902627D01*
X974249Y902443D01*
X973470Y901162D01*
X973654Y900406D01*
X972874Y899124D01*
X972119Y898940D01*
X862625Y718936D01*
X852899Y681058D01*
X879812Y548823D01*
X901723Y515082D01*
X923636Y481340D01*
X927651Y478896D01*
X930844D01*
G03X931672Y479239I0J1171D01*
G01X932429Y479996D01*
G03X932299Y480796I-354J353D01*
G01X932260Y480816D01*
X929331Y482283D01*
G01X1100932Y1031111D02*
X1099226D01*
G02X1098726Y1031611I0J500D01*
G01Y1033477D01*
G03X1096998Y1035205I-1728J0D01*
G01X1090002D01*
X1028340Y993484D01*
X861600Y719368D01*
X851770Y681087D01*
X878775Y548399D01*
X922849Y480530D01*
X927342Y477796D01*
X930845D01*
G03X932450Y478461I-1J2271D01*
G01X933654Y479665D01*
G02X934347Y479777I424J-424D01*
G01X937205Y478346D01*
G01X1099357Y1024025D02*
X1101063D01*
G03X1101563Y1024525I0J500D01*
G01Y1026391D01*
G03X1100936Y1027018I-627J0D01*
G01X1091309D01*
X1088105Y1024850D01*
X1087957Y1024086D01*
X1086715Y1023245D01*
X1085951Y1023392D01*
X1084709Y1022552D01*
X1084562Y1021788D01*
X1083320Y1020947D01*
X1082556Y1021095D01*
X1081314Y1020254D01*
X1081166Y1019490D01*
X1079924Y1018649D01*
X1079160Y1018797D01*
X1077918Y1017956D01*
X1077771Y1017192D01*
X1076528Y1016352D01*
X1075765Y1016499D01*
X1048535Y998072D01*
X1048377Y997252D01*
X1047135Y996412D01*
X1046315Y996570D01*
X1045073Y995729D01*
X1044915Y994910D01*
X1043673Y994069D01*
X1042853Y994227D01*
X1041611Y993386D01*
X1041453Y992567D01*
X1040211Y991726D01*
X1039392Y991884D01*
X1031466Y986521D01*
X1016622Y962110D01*
X1016807Y961354D01*
X1016027Y960072D01*
X1015271Y959888D01*
X1014492Y958606D01*
X1014676Y957851D01*
X1013897Y956569D01*
X1013141Y956385D01*
X1012362Y955103D01*
X1012546Y954348D01*
X1011767Y953066D01*
X1011011Y952882D01*
X1010231Y951600D01*
X1010416Y950845D01*
X1009636Y949563D01*
X1008880Y949379D01*
X998489Y932291D01*
X998673Y931535D01*
X997893Y930253D01*
X997138Y930069D01*
X996358Y928787D01*
X996542Y928032D01*
X995763Y926750D01*
X995007Y926566D01*
X994228Y925284D01*
X994412Y924529D01*
X993633Y923247D01*
X992877Y923063D01*
X917432Y799002D01*
X911583Y776223D01*
X871625Y620617D01*
X884927Y555125D01*
X921949Y498116D01*
X927652Y494644D01*
X930893D01*
G03X931637Y494952I0J1052D01*
G01X932429Y495744D01*
G03X932299Y496544I-354J353D01*
G01X932260Y496564D01*
X929331Y498031D01*
G01X1104869Y1024025D02*
X1103163D01*
G02X1102663Y1024525I0J500D01*
G01Y1026391D01*
G03X1100936Y1028118I-1727J0D01*
G01X1090971D01*
X1030651Y987298D01*
X916407Y799434D01*
X910517Y776497D01*
X870496Y620646D01*
X883890Y554701D01*
X902515Y526022D01*
X921162Y497306D01*
X927343Y493544D01*
X930893D01*
G03X932415Y494174I1J2152D01*
G01X933654Y495413D01*
G02X934347Y495525I424J-424D01*
G01X937205Y494094D01*
G01X1095420Y1016938D02*
X1097126D01*
G03X1097626Y1017438I0J500D01*
G01Y1019304D01*
G03X1096999Y1019931I-627J0D01*
G01X1091076D01*
X1086106Y1016569D01*
X1085948Y1015750D01*
X1084706Y1014909D01*
X1083886Y1015067D01*
X1082644Y1014227D01*
X1082486Y1013407D01*
X1081244Y1012567D01*
X1080424Y1012725D01*
X1079182Y1011884D01*
X1079024Y1011065D01*
X1077781Y1010225D01*
X1076962Y1010383D01*
X1058154Y997659D01*
X1058006Y996896D01*
X1056764Y996055D01*
X1056000Y996203D01*
X1054758Y995362D01*
X1054611Y994598D01*
X1053368Y993758D01*
X1052604Y993905D01*
X1051362Y993065D01*
X1051215Y992301D01*
X1049972Y991461D01*
X1049208Y991608D01*
X1047966Y990768D01*
X1047819Y990004D01*
X1046576Y989163D01*
X1045813Y989311D01*
X1035482Y982322D01*
X1032572Y977537D01*
X1032756Y976782D01*
X1031977Y975500D01*
X1031221Y975316D01*
X1030442Y974034D01*
X1030626Y973279D01*
X1029846Y971997D01*
X1029091Y971813D01*
X1028311Y970531D01*
X1028495Y969776D01*
X1027716Y968494D01*
X1026960Y968310D01*
X1026181Y967028D01*
X1026365Y966273D01*
X1025585Y964991D01*
X1024830Y964807D01*
X1001901Y927105D01*
X1002085Y926350D01*
X1001305Y925068D01*
X1000550Y924884D01*
X999770Y923602D01*
X999954Y922847D01*
X999175Y921565D01*
X998419Y921381D01*
X997640Y920099D01*
X997824Y919344D01*
X997044Y918062D01*
X996289Y917878D01*
X922760Y796977D01*
X877780Y621864D01*
X890646Y558666D01*
X918296Y516087D01*
X927650Y510392D01*
X931005D01*
G03X931558Y510621I0J782D01*
G01X932429Y511492D01*
G03X932299Y512292I-354J353D01*
G01X932260Y512312D01*
X929331Y513779D01*
G01X1100932Y1016938D02*
X1099226D01*
G02X1098726Y1017438I0J500D01*
G01Y1019304D01*
G03X1096999Y1021031I-1727J0D01*
G01X1090738D01*
X1034667Y983099D01*
X921735Y797409D01*
X876651Y621893D01*
X889609Y558242D01*
X917509Y515277D01*
X927341Y509292D01*
X931005D01*
G03X932336Y509843I0J1882D01*
G01X933654Y511161D01*
G02X934347Y511273I424J-424D01*
G01X937205Y509842D01*
G01X1104869Y1009852D02*
X1103163D01*
G02X1102663Y1010352I0J500D01*
G01Y1012218D01*
G03X1100936Y1013945I-1727J0D01*
G01X1090025D01*
X1039889Y980017D01*
X926560Y793674D01*
X894486Y668780D01*
X908482Y600026D01*
X928180Y588032D01*
X930916D01*
G03X932399Y588646I0J2097D01*
G01X933654Y589901D01*
G02X934347Y590013I424J-424D01*
G01X937205Y588582D01*
G01X1099357Y1009852D02*
X1101063D01*
G03X1101563Y1010352I0J500D01*
G01Y1012218D01*
G03X1100936Y1012845I-627J0D01*
G01X1090363D01*
X1086116Y1009971D01*
X1085958Y1009152D01*
X1084716Y1008311D01*
X1083896Y1008469D01*
X1082654Y1007628D01*
X1082496Y1006809D01*
X1081254Y1005968D01*
X1080435Y1006126D01*
X1079192Y1005286D01*
X1079034Y1004466D01*
X1077792Y1003626D01*
X1076973Y1003784D01*
X1057103Y990337D01*
X1056956Y989574D01*
X1055714Y988733D01*
X1054950Y988880D01*
X1053708Y988040D01*
X1053560Y987276D01*
X1052318Y986435D01*
X1051554Y986582D01*
X1050312Y985742D01*
X1050165Y984978D01*
X1048923Y984137D01*
X1048159Y984285D01*
X1046917Y983444D01*
X1046769Y982680D01*
X1045527Y981839D01*
X1044763Y981987D01*
X1040704Y979240D01*
X1039180Y976734D01*
X1039364Y975978D01*
X1038585Y974697D01*
X1037829Y974513D01*
X1037050Y973231D01*
X1037234Y972475D01*
X1036454Y971194D01*
X1035699Y971010D01*
X1034919Y969728D01*
X1035103Y968972D01*
X1034324Y967691D01*
X1033568Y967507D01*
X1032789Y966225D01*
X1032973Y965469D01*
X1032193Y964188D01*
X1031438Y964004D01*
X1008168Y925741D01*
X1008352Y924986D01*
X1007572Y923704D01*
X1006817Y923520D01*
X1006038Y922238D01*
X1006222Y921483D01*
X1005442Y920201D01*
X1004687Y920017D01*
X1003907Y918735D01*
X1004091Y917980D01*
X1003312Y916698D01*
X1002556Y916514D01*
X927585Y793242D01*
X911601Y730997D01*
X895615Y668751D01*
X909465Y600716D01*
X928489Y589132D01*
X930916D01*
G03X931621Y589424I0J997D01*
G01X932429Y590232D01*
G03X932299Y591032I-354J353D01*
G01X932260Y591052D01*
X929331Y592519D01*
G01X1095420Y1002765D02*
X1097126D01*
G03X1097626Y1003265I0J500D01*
G01Y1005131D01*
G03X1096999Y1005758I-627J0D01*
G01X1090136D01*
X1088045Y1004343D01*
X1087009Y1003642D01*
X1086862Y1002878D01*
X1085620Y1002037D01*
X1084856Y1002184D01*
X1083614Y1001344D01*
X1083466Y1000580D01*
X1082224Y999739D01*
X1081460Y999886D01*
X1080218Y999045D01*
X1080070Y998282D01*
X1078828Y997441D01*
X1078064Y997588D01*
X1063133Y987483D01*
X1062975Y986664D01*
X1061733Y985823D01*
X1060914Y985981D01*
X1059671Y985140D01*
X1059513Y984321D01*
X1058271Y983480D01*
X1057452Y983638D01*
X1056210Y982798D01*
X1056052Y981978D01*
X1054809Y981138D01*
X1053990Y981295D01*
X1051315Y979485D01*
X1047899Y973868D01*
X1048083Y973113D01*
X1047304Y971831D01*
X1046548Y971647D01*
X1045769Y970365D01*
X1045953Y969609D01*
X1045173Y968328D01*
X1044418Y968144D01*
X1043638Y966862D01*
X1043822Y966106D01*
X1043043Y964825D01*
X1042287Y964641D01*
X1041508Y963359D01*
X1041692Y962603D01*
X1040912Y961322D01*
X1040157Y961138D01*
X1029764Y944050D01*
X1029948Y943294D01*
X1029169Y942013D01*
X1028413Y941828D01*
X1027634Y940547D01*
X1027818Y939791D01*
X1027038Y938510D01*
X1026283Y938325D01*
X1025503Y937044D01*
X1025687Y936288D01*
X1024908Y935006D01*
X1024152Y934822D01*
X1023373Y933541D01*
X1023557Y932785D01*
X1022777Y931503D01*
X1022022Y931319D01*
X930016Y780042D01*
X916018Y725551D01*
X902020Y671062D01*
X902019Y671061D01*
X913886Y612786D01*
X927707Y604880D01*
X930909D01*
G03X931626Y605177I0J1014D01*
G01X932429Y605980D01*
G03X932299Y606780I-360J352D01*
G01X932260Y606800D01*
X929331Y608267D01*
G01X1100932Y1002765D02*
X1099226D01*
G02X1098726Y1003265I0J500D01*
G01Y1005131D01*
G03X1096999Y1006858I-1727J0D01*
G01X1089799D01*
X1089198Y1006453D01*
X1087951Y1005609D01*
X1087952D01*
X1050500Y980262D01*
X928991Y780474D01*
X914952Y725825D01*
X901000Y671515D01*
X900850Y671288D01*
X912907Y612078D01*
X927414Y603780D01*
X930910D01*
G03X932404Y604399I-1J2114D01*
G01X933654Y605649D01*
G02X934347Y605761I424J-424D01*
G01X937205Y604330D01*
G01X1099357Y995678D02*
X1101063D01*
G03X1101563Y996178I0J500D01*
G01Y998044D01*
G03X1100936Y998671I-627J0D01*
G01X1090386D01*
X1076498Y989272D01*
X1076340Y988452D01*
X1075098Y987611D01*
X1074279Y987769D01*
X1073037Y986929D01*
X1072879Y986109D01*
X1071636Y985269D01*
X1070817Y985426D01*
X1069575Y984586D01*
X1069417Y983766D01*
X1068175Y982926D01*
X1067356Y983084D01*
X1059050Y977462D01*
Y977461D01*
X1058271Y976179D01*
X1058455Y975424D01*
X1057675Y974142D01*
X1056919Y973958D01*
X1056140Y972676D01*
X1056324Y971921D01*
X1055545Y970639D01*
X1054789Y970455D01*
X1054010Y969173D01*
X1054194Y968418D01*
X1053414Y967136D01*
X1052658Y966952D01*
X1051879Y965670D01*
X1052063Y964915D01*
X1051284Y963633D01*
X1050528Y963449D01*
X1040135Y946361D01*
X1040319Y945606D01*
X1039540Y944324D01*
X1038784Y944140D01*
X1038005Y942858D01*
X1038189Y942103D01*
X1037409Y940821D01*
X1036654Y940637D01*
X1035874Y939355D01*
X1036058Y938600D01*
X1035279Y937318D01*
X1034523Y937134D01*
X1033744Y935852D01*
X1033928Y935097D01*
X1033148Y933815D01*
X1032393Y933631D01*
X1019222Y911976D01*
X1019406Y911220D01*
X1018627Y909938D01*
X1017871Y909754D01*
X1017092Y908473D01*
X1017276Y907717D01*
X1016496Y906436D01*
X1015741Y906251D01*
X1014961Y904970D01*
X1015145Y904214D01*
X1014366Y902933D01*
X1013610Y902748D01*
X932688Y769697D01*
X929790Y758410D01*
X929789D01*
X909231Y678362D01*
Y678353D01*
X920047Y625253D01*
X927651Y620628D01*
X930869D01*
G03X931654Y620953I0J1110D01*
G01X932429Y621728D01*
G03X932299Y622528I-354J353D01*
G01X932260Y622548D01*
X929331Y624015D01*
G01X1104869Y995678D02*
X1103163D01*
G02X1102663Y996178I0J500D01*
G01Y998044D01*
G03X1100936Y999771I-1727J0D01*
G01X1090048D01*
X1058346Y978314D01*
X1058178Y978146D01*
X931663Y770129D01*
X928689Y758554D01*
Y758549D01*
X908131Y678501D01*
Y678242D01*
X919064Y624562D01*
X927342Y619528D01*
X930869D01*
G03X932432Y620175I1J2210D01*
G01X933654Y621397D01*
G02X934347Y621509I424J-424D01*
G01X937205Y620078D01*
G01X1095420Y988592D02*
X1097126D01*
G03X1097626Y989092I0J500D01*
G01Y990958D01*
G03X1096999Y991585I-627J0D01*
G01X1090750D01*
X1084299Y987219D01*
X1084141Y986400D01*
X1082899Y985559D01*
X1082079Y985717D01*
X1080837Y984877D01*
X1080679Y984057D01*
X1079437Y983217D01*
X1078618Y983374D01*
X1077375Y982534D01*
X1077217Y981714D01*
X1075975Y980874D01*
X1075156Y981032D01*
X1069847Y977439D01*
X1069068Y976157D01*
X1069252Y975402D01*
X1068472Y974120D01*
X1067716Y973936D01*
X1066937Y972654D01*
X1067121Y971899D01*
X1066342Y970617D01*
X1065586Y970433D01*
X1064807Y969151D01*
X1064991Y968396D01*
X1064211Y967114D01*
X1063455Y966930D01*
X1062676Y965648D01*
X1062860Y964893D01*
X1062081Y963611D01*
X1061325Y963427D01*
X1050932Y946339D01*
X1051116Y945584D01*
X1050337Y944302D01*
X1049581Y944118D01*
X1048802Y942836D01*
X1048986Y942081D01*
X1048206Y940799D01*
X1047451Y940615D01*
X1046671Y939333D01*
X1046855Y938578D01*
X1046076Y937296D01*
X1045320Y937112D01*
X1044541Y935830D01*
X1044725Y935075D01*
X1043945Y933793D01*
X1043190Y933609D01*
X1028492Y909442D01*
X1028676Y908687D01*
X1027897Y907405D01*
X1027141Y907221D01*
X1026361Y905939D01*
X1026545Y905184D01*
X1025766Y903902D01*
X1025010Y903718D01*
X1024231Y902437D01*
X1024415Y901681D01*
X1023636Y900399D01*
X1022880Y900215D01*
X935002Y755726D01*
X916293Y682872D01*
X916288Y682865D01*
X920600Y661689D01*
X920601Y661688D01*
X920667Y661364D01*
Y661363D01*
X925487Y637695D01*
X927648Y636379D01*
X927990D01*
Y636378D01*
X930857D01*
G03X931666Y636713I0J1144D01*
G01X932429Y637476D01*
G03X932299Y638276I-354J353D01*
G01X932260Y638296D01*
X929331Y639763D01*
G01X1100932Y988592D02*
X1099226D01*
G02X1098726Y989092I0J500D01*
G01Y990958D01*
G03X1096999Y992685I-1727J0D01*
G01X1090412D01*
X1069031Y978216D01*
X1069032D01*
X933977Y756158D01*
X915273Y683325D01*
X915119Y683092D01*
X919588Y661145D01*
X919589Y661144D01*
X924504Y637004D01*
Y637005D01*
X927339Y635279D01*
Y635278D01*
X930857D01*
G03X932444Y635935I0J2244D01*
G01X933654Y637145D01*
G02X934347Y637257I424J-424D01*
G01X937205Y635826D01*
G01X1127703Y1038198D02*
X1129409D01*
G03X1129909Y1038698I0J500D01*
G01Y1040564D01*
G02X1131636Y1042291I1727J0D01*
G01X1143936D01*
X1189599Y1033024D01*
X1217653Y1016212D01*
X1224839Y1005147D01*
X1232330Y969907D01*
Y969905D01*
X1221647Y921702D01*
Y921703D01*
X1027671Y623006D01*
X1022983Y599990D01*
X1008828Y530495D01*
X959938Y464027D01*
X956177Y462048D01*
X952981D01*
X950513Y459580D01*
G03Y458858I361J-361D01*
G01X951087Y457716D01*
X951138Y457613D01*
X951230Y457432D01*
G03X951971Y457184I494J245D01*
G01X954921Y458661D01*
G01X1133215Y1038198D02*
X1131509D01*
G02X1131009Y1038698I0J500D01*
G01Y1040564D01*
G02X1131636Y1041191I627J0D01*
G01X1143825D01*
X1189195Y1031983D01*
X1216869Y1015399D01*
X1223805Y1004719D01*
X1231204Y969910D01*
X1220615Y922136D01*
X1219143Y919869D01*
X1218327Y919696D01*
X1217510Y918438D01*
X1217683Y917621D01*
X1216866Y916363D01*
X1216050Y916190D01*
X1215233Y914932D01*
X1215406Y914115D01*
X1214589Y912857D01*
X1213773Y912684D01*
X1212956Y911426D01*
X1213129Y910609D01*
X1182989Y864197D01*
X1182173Y864024D01*
X1181356Y862766D01*
X1181530Y861950D01*
X1180713Y860692D01*
X1179896Y860518D01*
X1179079Y859260D01*
X1179253Y858444D01*
X1178436Y857186D01*
X1177620Y857012D01*
X1176803Y855754D01*
X1176976Y854938D01*
Y854937D01*
X1026634Y623430D01*
X1007798Y530952D01*
X959202Y464883D01*
X955905Y463148D01*
X952525D01*
X949735Y460358D01*
G03X949586Y458250I1139J-1140D01*
G01X950102Y457224D01*
Y457223D01*
X950103D01*
X950267Y456896D01*
G02X950044Y456225I-447J-224D01*
G01X947047Y454724D01*
G01X1123766Y1031111D02*
X1125472D01*
G03X1125972Y1031611I0J500D01*
G01Y1033477D01*
G02X1127699Y1035204I1727J0D01*
G01X1138643D01*
X1192961Y1024177D01*
X1213669Y1011768D01*
X1219167Y1003286D01*
X1227370Y964708D01*
X1219933Y931146D01*
X1219932Y931143D01*
X1021095Y624996D01*
X1003620Y539162D01*
X959863Y479671D01*
X956387Y477796D01*
X952981D01*
X950513Y475328D01*
G03Y474606I361J-361D01*
G01X951087Y473464D01*
X951138Y473361D01*
X951230Y473180D01*
G03X951971Y472932I494J245D01*
G01X954921Y474409D01*
G01X1129278Y1031111D02*
X1127572D01*
G02X1127072Y1031611I0J500D01*
G01Y1033477D01*
G02X1127699Y1034104I627J0D01*
G01X1138532D01*
X1158671Y1030015D01*
X1159132Y1029320D01*
X1160602Y1029021D01*
X1161298Y1029482D01*
X1162768Y1029184D01*
X1163229Y1028488D01*
X1164699Y1028190D01*
X1165394Y1028651D01*
X1166864Y1028352D01*
X1167325Y1027656D01*
X1168795Y1027358D01*
X1169491Y1027819D01*
X1192557Y1023136D01*
X1212884Y1010955D01*
X1218133Y1002858D01*
X1226244Y964712D01*
X1218900Y931576D01*
X1214635Y925010D01*
X1213874Y924848D01*
X1213057Y923590D01*
X1213219Y922829D01*
X1212402Y921571D01*
X1211641Y921409D01*
X1210824Y920152D01*
X1210986Y919391D01*
X1210169Y918133D01*
X1209408Y917971D01*
X1208591Y916713D01*
X1208753Y915952D01*
X1020058Y625420D01*
X1002590Y539619D01*
X959123Y480522D01*
X956109Y478896D01*
X952525D01*
X949735Y476106D01*
G03X949586Y473998I1139J-1140D01*
G01X950102Y472972D01*
Y472971D01*
X950103D01*
X950267Y472644D01*
G02X950044Y471973I-447J-224D01*
G01X947047Y470472D01*
G01X1127703Y1024025D02*
X1129409D01*
G03X1129909Y1024525I0J500D01*
G01Y1026391D01*
G02X1131636Y1028118I1727J0D01*
G01X1141943D01*
X1191621Y1018033D01*
X1200361Y1012795D01*
X1209159Y1007523D01*
X1215568Y997655D01*
X1222562Y964767D01*
X1215833Y934404D01*
X1114850Y778885D01*
X1013869Y623366D01*
X998387Y547794D01*
X960170Y495836D01*
X956318Y493544D01*
X952981D01*
X950513Y491076D01*
G03Y490354I361J-361D01*
G01X951087Y489212D01*
X951138Y489109D01*
X951230Y488928D01*
G03X951971Y488680I494J245D01*
G01X954921Y490157D01*
G01X1133215Y1024025D02*
X1131509D01*
G02X1131009Y1024525I0J500D01*
G01Y1026391D01*
G02X1131636Y1027018I627J0D01*
G01X1141832D01*
X1161743Y1022976D01*
X1162204Y1022280D01*
X1163674Y1021982D01*
X1164369Y1022442D01*
X1165839Y1022144D01*
X1166300Y1021448D01*
X1167770Y1021150D01*
X1168466Y1021611D01*
X1169936Y1021312D01*
X1170397Y1020617D01*
X1171867Y1020318D01*
X1172562Y1020779D01*
X1191217Y1016992D01*
X1208375Y1006710D01*
X1214534Y997227D01*
X1217591Y982852D01*
X1217137Y982152D01*
X1217449Y980685D01*
X1218148Y980231D01*
X1218460Y978763D01*
X1218006Y978064D01*
X1218318Y976596D01*
X1219018Y976142D01*
X1219330Y974675D01*
X1218876Y973975D01*
X1219188Y972508D01*
X1219887Y972053D01*
X1221436Y964772D01*
X1214801Y934837D01*
X1012833Y623791D01*
X997357Y548252D01*
X959415Y496668D01*
X956015Y494644D01*
X952525D01*
X949735Y491854D01*
G03X949586Y489746I1139J-1140D01*
G01X950102Y488720D01*
Y488719D01*
X950103D01*
X950267Y488392D01*
G02X950044Y487721I-447J-224D01*
G01X947047Y486220D01*
G01X1129278Y1016938D02*
X1127572D01*
G02X1127072Y1017438I0J500D01*
G01Y1019304D01*
G02X1127699Y1019931I627J0D01*
G01X1142747D01*
X1191957Y1009939D01*
X1203930Y1002766D01*
X1209953Y993490D01*
X1216132Y964434D01*
X1210451Y938797D01*
X1207659Y934498D01*
X1206843Y934325D01*
X1206026Y933067D01*
X1206200Y932250D01*
X1205383Y930992D01*
X1204566Y930819D01*
X1203750Y929561D01*
X1203923Y928745D01*
X1203106Y927487D01*
X1202290Y927313D01*
X1201473Y926055D01*
X1201646Y925239D01*
X1157201Y856799D01*
X1156384Y856626D01*
X1155567Y855368D01*
X1155741Y854551D01*
X1154924Y853293D01*
X1154108Y853120D01*
X1153291Y851862D01*
X1153464Y851046D01*
X1152647Y849788D01*
X1151831Y849614D01*
X1151014Y848356D01*
X1151188Y847540D01*
X1006830Y625246D01*
X993043Y557563D01*
X960513Y513338D01*
X956059Y510392D01*
X952574D01*
X949764Y507582D01*
G03X949466Y505729I1131J-1132D01*
G01X950267Y504140D01*
Y504139D01*
G02X950044Y503468I-447J-224D01*
G01X947047Y501968D01*
G01X1123766Y1016938D02*
X1125472D01*
G03X1125972Y1017438I0J500D01*
G01Y1019304D01*
G02X1127699Y1021031I1727J0D01*
G01X1142858D01*
X1192361Y1010980D01*
X1204714Y1003579D01*
X1210987Y993918D01*
X1217258Y964429D01*
X1211483Y938364D01*
X1007867Y624822D01*
X1001015Y591186D01*
X999292Y582727D01*
X994073Y557106D01*
X961284Y512528D01*
X956390Y509292D01*
X953030D01*
X950542Y506804D01*
G03X950449Y506225I354J-354D01*
G01X951251Y504634D01*
Y504633D01*
X951253Y504629D01*
Y504628D01*
G03X951924Y504405I447J224D01*
G01X954921Y505905D01*
G01X1127703Y1009852D02*
X1129409D01*
G03X1129909Y1010352I0J500D01*
G01Y1012218D01*
G02X1131636Y1013945I1727J0D01*
G01X1138087D01*
X1144017Y1009843D01*
X1149980Y1005719D01*
X1153895Y992987D01*
X1147893Y968934D01*
X1161936Y905590D01*
X1152371Y862441D01*
X1008181Y636121D01*
X957415Y603780D01*
X952981D01*
X950513Y601312D01*
G03Y600590I361J-361D01*
G01X951087Y599448D01*
X951138Y599345D01*
X951230Y599164D01*
G03X951971Y598916I494J245D01*
G01X954921Y600393D01*
G01X1133215Y1009852D02*
X1131509D01*
G02X1131009Y1010352I0J500D01*
G01Y1012218D01*
G02X1131636Y1012845I627J0D01*
G01X1137743D01*
X1149040Y1005031D01*
X1152753Y992956D01*
X1146762Y968949D01*
X1147087Y967485D01*
X1146638Y966781D01*
X1146963Y965316D01*
X1147667Y964868D01*
X1147991Y963404D01*
X1147543Y962700D01*
X1147868Y961235D01*
X1148572Y960787D01*
X1148896Y959323D01*
X1148448Y958619D01*
X1148773Y957155D01*
X1149476Y956706D01*
X1156205Y926354D01*
X1155757Y925650D01*
X1156082Y924185D01*
X1156786Y923737D01*
X1157110Y922273D01*
X1156662Y921569D01*
X1156987Y920104D01*
X1157690Y919656D01*
X1158015Y918192D01*
X1157567Y917488D01*
X1157891Y916024D01*
X1158595Y915575D01*
X1160809Y905590D01*
X1151338Y862869D01*
X1007384Y636918D01*
X957094Y604880D01*
X952525D01*
X949735Y602090D01*
G03X949586Y599982I1139J-1140D01*
G01X950102Y598956D01*
Y598955D01*
X950103D01*
X950267Y598628D01*
G02X950044Y597957I-447J-224D01*
G01X947047Y596456D01*
G01X1123766Y1002765D02*
X1125472D01*
G03X1125972Y1003265I0J500D01*
G01Y1005131D01*
G02X1127699Y1006858I1727J0D01*
G01X1136042D01*
X1145345Y1000431D01*
X1146882Y995432D01*
X1148397Y990506D01*
X1143064Y969136D01*
X1156718Y907555D01*
X1147358Y865329D01*
X1013485Y655181D01*
X957521Y619528D01*
X952981D01*
X950513Y617060D01*
G03Y616338I361J-361D01*
G01X951087Y615196D01*
X951138Y615093D01*
X951230Y614912D01*
G03X951971Y614664I494J245D01*
G01X954921Y616141D01*
G01X1129278Y1002765D02*
X1127572D01*
G02X1127072Y1003265I0J500D01*
G01Y1005131D01*
G02X1127699Y1005758I627J0D01*
G01X1135698D01*
X1144405Y999742D01*
X1145116Y997427D01*
X1145117D01*
X1145830Y995108D01*
X1147255Y990475D01*
X1141933Y969151D01*
X1142258Y967687D01*
X1141809Y966983D01*
X1142134Y965518D01*
X1142838Y965070D01*
X1143163Y963606D01*
X1142714Y962902D01*
X1143039Y961438D01*
X1143743Y960989D01*
X1144067Y959525D01*
X1143619Y958821D01*
X1143944Y957357D01*
X1144648Y956908D01*
X1150463Y930680D01*
X1150015Y929976D01*
X1150340Y928512D01*
X1151044Y928064D01*
X1151368Y926599D01*
X1150920Y925895D01*
X1151245Y924431D01*
X1151948Y923983D01*
X1152273Y922518D01*
X1151825Y921815D01*
X1152150Y920350D01*
X1152853Y919902D01*
X1155591Y907555D01*
X1146325Y865757D01*
X1012688Y655978D01*
X984945Y638304D01*
X957199Y620628D01*
X952525D01*
X949735Y617838D01*
G03X949586Y615730I1139J-1140D01*
G01X950102Y614704D01*
Y614703D01*
X950103D01*
X950267Y614376D01*
G02X950044Y613705I-447J-224D01*
G01X947047Y612204D01*
G01X1127703Y995678D02*
X1129409D01*
G03X1129909Y996178I0J500D01*
G01Y998044D01*
G02X1131636Y999771I1727J0D01*
G01X1138288D01*
X1140442Y998284D01*
X1142896Y989283D01*
X1143053Y989021D01*
X1137502Y966797D01*
X1150690Y907295D01*
X1142526Y870176D01*
X1017422Y673794D01*
X956963Y635276D01*
X952981D01*
X950513Y632808D01*
G03Y632086I361J-361D01*
G01X951087Y630944D01*
X951138Y630841D01*
X951230Y630660D01*
G03X951971Y630412I494J245D01*
G01X954921Y631889D01*
G01X1133215Y995678D02*
X1131509D01*
G02X1131009Y996178I0J500D01*
G01Y998044D01*
G02X1131636Y998671I627J0D01*
G01X1137945D01*
X1139486Y997607D01*
X1141874Y988847D01*
X1141875Y988846D01*
X1141874D01*
X1136371Y966812D01*
X1136696Y965348D01*
X1136247Y964644D01*
X1136572Y963179D01*
X1137276Y962731D01*
X1137600Y961267D01*
X1137152Y960563D01*
X1137476Y959098D01*
X1138180Y958650D01*
X1138505Y957186D01*
X1138056Y956482D01*
X1138381Y955017D01*
X1139085Y954569D01*
X1146506Y921087D01*
X1146058Y920383D01*
X1146382Y918919D01*
X1147086Y918470D01*
X1147410Y917006D01*
X1146962Y916302D01*
X1147287Y914838D01*
X1147990Y914389D01*
X1148315Y912925D01*
X1147867Y912221D01*
X1148191Y910757D01*
X1148895Y910308D01*
X1149563Y907294D01*
X1141493Y870603D01*
X1016625Y674591D01*
X956642Y636376D01*
X952525D01*
X949735Y633586D01*
G03X949586Y631478I1139J-1140D01*
G01X950102Y630452D01*
Y630451D01*
X950103D01*
X950267Y630124D01*
G02X950044Y629453I-447J-224D01*
G01X947047Y627952D01*
G01X1123766Y988592D02*
X1125472D01*
G03X1125972Y989092I0J500D01*
G01Y990958D01*
G02X1127699Y992685I1727J0D01*
G01X1134477D01*
X1136348Y991392D01*
X1137152Y988771D01*
X1137151Y988770D01*
X1131661Y966604D01*
X1144911Y906835D01*
X1138028Y875783D01*
X1079118Y783311D01*
X1020181Y690795D01*
X988999Y670930D01*
X957752Y651024D01*
X953013D01*
X952199Y650209D01*
X952198D01*
X950513Y648524D01*
G03Y647834I345J-345D01*
G01X951087Y646692D01*
X951138Y646589D01*
X951230Y646408D01*
G03X951971Y646160I494J245D01*
G01X954921Y647637D01*
G01X1129278Y988592D02*
X1127572D01*
G02X1127072Y989092I0J500D01*
G01Y990958D01*
G02X1127699Y991585I627J0D01*
G01X1134133D01*
X1135408Y990704D01*
X1136010Y988741D01*
Y988740D01*
X1130531Y966618D01*
X1130856Y965154D01*
X1130407Y964450D01*
X1130732Y962985D01*
X1131436Y962537D01*
X1131760Y961073D01*
X1131312Y960369D01*
X1131637Y958904D01*
X1132340Y958456D01*
X1132665Y956992D01*
X1132217Y956288D01*
X1132541Y954824D01*
X1133245Y954375D01*
X1140796Y920311D01*
X1140348Y919607D01*
X1140673Y918143D01*
X1141376Y917695D01*
X1141701Y916230D01*
X1141253Y915526D01*
X1141577Y914062D01*
X1142281Y913614D01*
X1142606Y912149D01*
X1142158Y911445D01*
X1142482Y909981D01*
X1143186Y909533D01*
X1143784Y906835D01*
X1136995Y876211D01*
X1019384Y691592D01*
X957431Y652124D01*
X952557D01*
X949735Y649302D01*
G03X949586Y647227I1123J-1123D01*
G01X950102Y646200D01*
Y646199D01*
X950103D01*
X950267Y645872D01*
G02X950044Y645201I-447J-224D01*
G01X947047Y643700D01*
G01X1447835Y120276D02*
Y118447D01*
G02X1447335Y117947I-500J0D01*
G01X1445651D01*
G02X1444841Y118757I0J810D01*
G01Y122008D01*
X1443652Y123754D01*
X1438306Y127287D01*
X1417128Y131936D01*
X1308245Y109479D01*
X1242664Y122391D01*
X1166773Y105556D01*
X1148328Y93575D01*
X1123525Y55382D01*
X1116725Y48582D01*
X1104187D01*
G03X1101923Y47644I1J-3203D01*
G01X1100992Y46713D01*
G02X1100299Y46601I-424J424D01*
G01X1097441Y48032D01*
G01X1447835Y114764D02*
Y116347D01*
G03X1447335Y116847I-500J0D01*
G01X1445651D01*
G02X1443741Y118757I0J1910D01*
G01Y121668D01*
X1442864Y122955D01*
X1437870Y126256D01*
X1417121Y130811D01*
X1308250Y108356D01*
X1242677Y121267D01*
X1223808Y117081D01*
X1204940Y112895D01*
X1167206Y104524D01*
X1149124Y92779D01*
X1131087Y65006D01*
X1131249Y64245D01*
X1130432Y62987D01*
X1129671Y62826D01*
X1128854Y61568D01*
X1129016Y60807D01*
X1128199Y59549D01*
X1127438Y59387D01*
X1126621Y58129D01*
X1126783Y57368D01*
X1125966Y56110D01*
X1125205Y55949D01*
X1124385Y54686D01*
X1117181Y47482D01*
X1104188D01*
G03X1102701Y46866I0J-2103D01*
G01X1102217Y46382D01*
G03X1102347Y45582I354J-353D01*
G01X1102386Y45562D01*
X1105315Y44095D01*
G01X1504528Y120276D02*
Y118447D01*
G02X1504028Y117947I-500J0D01*
G01X1502344D01*
G02X1501534Y118757I0J810D01*
G01Y122232D01*
X1499461Y125278D01*
X1497085Y126822D01*
X1432760Y140985D01*
X1340805Y121960D01*
X1310301Y115648D01*
X1223690Y132826D01*
X1207315Y129439D01*
X1191374Y126139D01*
X1147697Y134801D01*
X1147265Y135447D01*
X1145793Y135739D01*
X1145147Y135307D01*
X1143676Y135598D01*
X1143243Y136245D01*
X1141772Y136537D01*
X1141125Y136104D01*
X1125514Y139200D01*
X1121009D01*
G02X1120110Y139754I0J1007D01*
G01X1119976Y140020D01*
Y140021D01*
X1119975D01*
X1119811Y140348D01*
G02X1120034Y141019I447J224D01*
G01X1123031Y142520D01*
G01X1504528Y114764D02*
Y116347D01*
G03X1504028Y116847I-500J0D01*
G01X1502344D01*
G02X1500434Y118757I0J1910D01*
G01Y121893D01*
X1498676Y124476D01*
X1496653Y125790D01*
X1432753Y139860D01*
X1310306Y114525D01*
X1223695Y131703D01*
X1191379Y125016D01*
X1125405Y138100D01*
X1120950D01*
G02X1119151Y139209I0J2013D01*
G01X1118848Y139812D01*
G03X1118107Y140060I-494J-245D01*
G01X1115157Y138583D01*
M02*
